FILE_TYPE = MACRO_DRAWING;
SET COLOR_WIRE YELLOW;
SET COLOR_PROP ORANGE;
SET COLOR_DOT WHITE;
SET COLOR_ARC YELLOW;
SET COLOR_BODY GREEN;
SET COLOR_NOTE PURPLE;
SET PROP_DISPLAY VALUE;
SET PAGE_NUMBER P160;
FORCEADD UNIVERSAL_GND..1
(-6250 1125);
FORCEPROP 3 LASTPIN (-6250 1175) SIG_NAME GND\g
J 0
(-6240 1185);
DISPLAY 0.659574 (-6240 1185);
PAINT MONO (-6240 1185);
DISPLAY INVISIBLE (-6240 1185);
FORCEPROP 2 LAST CDS_LIB pure_quanta_power
J 0
(-6250 1125);
DISPLAY INVISIBLE (-6250 1125);
FORCEPROP 1 LAST HDL_POWER GND
J 1
(-6225 1050);
DISPLAY 0.872340 (-6225 1050);
PAINT GREEN (-6225 1050);
DISPLAY INVISIBLE (-6225 1050);
FORCEPROP 1 LAST PATH I1
J 0
(-6175 1125);
DISPLAY 0.872340 (-6175 1125);
PAINT AQUA (-6175 1125);
DISPLAY INVISIBLE (-6175 1125);
FORCEADD OFFPAGE..1
(-6700 3575);
FORCEPROP 2 LAST $XR0 151 
J 0
(-6982 3575);
DISPLAY 0.638298 (-6982 3575);
PAINT MONO (-6982 3575);
FORCEPROP 2 LAST CDS_LIB standard
J 0
(-6700 3575);
DISPLAY INVISIBLE (-6700 3575);
FORCEPROP 1 LAST OFFPAGE TRUE
J 0
(-6375 3450);
DISPLAY 1.170213 (-6375 3450);
PAINT GREEN (-6375 3450);
DISPLAY INVISIBLE (-6375 3450);
FORCEPROP 1 LAST COMMENT_BODY TRUE
J 0
(-6575 3475);
DISPLAY 1.170213 (-6575 3475);
PAINT GREEN (-6575 3475);
DISPLAY INVISIBLE (-6575 3475);
FORCEPROP 2 LAST PATH I10
J 0
(-6950 3625);
DISPLAY 0.680851 (-6950 3625);
DISPLAY INVISIBLE (-6950 3625);
FORCEADD OFFPAGE..1
(-6525 3725);
FORCEPROP 2 LAST $XR0 182 
J 0
(-6777 3725);
DISPLAY 0.638298 (-6777 3725);
PAINT MONO (-6777 3725);
FORCEPROP 2 LAST CDS_LIB standard
J 2
(-6525 3725);
DISPLAY INVISIBLE (-6525 3725);
FORCEPROP 1 LAST OFFPAGE TRUE
J 0
(-6200 3600);
DISPLAY 1.170213 (-6200 3600);
PAINT GREEN (-6200 3600);
DISPLAY INVISIBLE (-6200 3600);
FORCEPROP 1 LAST COMMENT_BODY TRUE
J 0
(-6400 3625);
DISPLAY 1.170213 (-6400 3625);
PAINT GREEN (-6400 3625);
DISPLAY INVISIBLE (-6400 3625);
FORCEPROP 2 LAST PATH I11
J 0
(-6775 3775);
DISPLAY 0.680851 (-6775 3775);
DISPLAY INVISIBLE (-6775 3775);
FORCEADD OFFPAGE..1
(-6700 3625);
FORCEPROP 2 LAST $XR0 151 
J 0
(-6982 3625);
DISPLAY 0.638298 (-6982 3625);
PAINT MONO (-6982 3625);
FORCEPROP 2 LAST CDS_LIB standard
J 0
(-6700 3625);
DISPLAY INVISIBLE (-6700 3625);
FORCEPROP 1 LAST OFFPAGE TRUE
J 0
(-6375 3500);
DISPLAY 1.170213 (-6375 3500);
PAINT GREEN (-6375 3500);
DISPLAY INVISIBLE (-6375 3500);
FORCEPROP 1 LAST COMMENT_BODY TRUE
J 0
(-6575 3525);
DISPLAY 1.170213 (-6575 3525);
PAINT GREEN (-6575 3525);
DISPLAY INVISIBLE (-6575 3525);
FORCEPROP 2 LAST PATH I12
J 0
(-6950 3675);
DISPLAY 0.680851 (-6950 3675);
DISPLAY INVISIBLE (-6950 3675);
FORCEADD OFFPAGE..1
(-6525 3825);
FORCEPROP 2 LAST $XR0 28 
J 0
(-6746 3825);
DISPLAY 0.638298 (-6746 3825);
PAINT MONO (-6746 3825);
FORCEPROP 2 LAST CDS_LIB standard
J 0
(-6525 3825);
DISPLAY INVISIBLE (-6525 3825);
FORCEPROP 1 LAST OFFPAGE TRUE
J 0
(-6200 3700);
DISPLAY 1.170213 (-6200 3700);
PAINT GREEN (-6200 3700);
DISPLAY INVISIBLE (-6200 3700);
FORCEPROP 1 LAST COMMENT_BODY TRUE
J 0
(-6400 3725);
DISPLAY 1.170213 (-6400 3725);
PAINT GREEN (-6400 3725);
DISPLAY INVISIBLE (-6400 3725);
FORCEPROP 2 LAST PATH I13
J 0
(-6775 3875);
DISPLAY 0.680851 (-6775 3875);
DISPLAY INVISIBLE (-6775 3875);
FORCEADD UNIVERSAL_POWER..1
(-6250 2150);
FORCEPROP 3 LASTPIN (-6250 2100) SIG_NAME P3V3_AUX\g
J 0
(-6240 2110);
DISPLAY 0.659574 (-6240 2110);
PAINT MONO (-6240 2110);
DISPLAY INVISIBLE (-6240 2110);
FORCEPROP 1 LAST HDL_POWER P3V3_AUX
J 1
(-6250 2200);
DISPLAY 0.872340 (-6250 2200);
PAINT YELLOW (-6250 2200);
FORCEPROP 2 LAST CDS_LIB pure_quanta_power
J 0
(-6250 2150);
DISPLAY INVISIBLE (-6250 2150);
FORCEPROP 1 LAST PATH I14
J 0
(-6200 2175);
DISPLAY 0.872340 (-6200 2175);
PAINT AQUA (-6200 2175);
DISPLAY INVISIBLE (-6200 2175);
FORCEADD OFFPAGE..1
(-6525 3875);
FORCEPROP 2 LAST $XR0 28 
J 0
(-6746 3875);
DISPLAY 0.638298 (-6746 3875);
PAINT MONO (-6746 3875);
FORCEPROP 2 LAST CDS_LIB standard
J 0
(-6525 3875);
DISPLAY INVISIBLE (-6525 3875);
FORCEPROP 1 LAST OFFPAGE TRUE
J 0
(-6200 3750);
DISPLAY 1.170213 (-6200 3750);
PAINT GREEN (-6200 3750);
DISPLAY INVISIBLE (-6200 3750);
FORCEPROP 1 LAST COMMENT_BODY TRUE
J 0
(-6400 3775);
DISPLAY 1.170213 (-6400 3775);
PAINT GREEN (-6400 3775);
DISPLAY INVISIBLE (-6400 3775);
FORCEPROP 2 LAST PATH I15
J 0
(-6775 3925);
DISPLAY 0.680851 (-6775 3925);
DISPLAY INVISIBLE (-6775 3925);
FORCEADD UNIVERSAL_GND..1
(-7125 4700);
FORCEPROP 3 LASTPIN (-7125 4750) SIG_NAME GND\g
J 0
(-7115 4760);
DISPLAY 0.659574 (-7115 4760);
PAINT MONO (-7115 4760);
DISPLAY INVISIBLE (-7115 4760);
FORCEPROP 2 LAST CDS_LIB pure_quanta_power
J 0
(-7125 4700);
DISPLAY INVISIBLE (-7125 4700);
FORCEPROP 1 LAST HDL_POWER GND
J 1
(-7100 4625);
DISPLAY 0.872340 (-7100 4625);
PAINT GREEN (-7100 4625);
DISPLAY INVISIBLE (-7100 4625);
FORCEPROP 1 LAST PATH I16
J 0
(-7050 4700);
DISPLAY 0.872340 (-7050 4700);
PAINT AQUA (-7050 4700);
DISPLAY INVISIBLE (-7050 4700);
FORCEADD UNIVERSAL_POWER..1
(-7125 5325);
FORCEPROP 3 LASTPIN (-7125 5275) SIG_NAME P3V3_9ZXL045_P0_VDDR\g
J 0
(-7115 5285);
DISPLAY 0.659574 (-7115 5285);
PAINT MONO (-7115 5285);
DISPLAY INVISIBLE (-7115 5285);
FORCEPROP 1 LAST HDL_POWER P3V3_9ZXL045_P0_VDDR
J 1
(-7125 5375);
DISPLAY 0.872340 (-7125 5375);
PAINT SKYBLUE (-7125 5375);
FORCEPROP 2 LAST CDS_LIB pure_quanta_power
J 0
(-7125 5325);
DISPLAY INVISIBLE (-7125 5325);
FORCEPROP 1 LAST PATH I17
J 0
(-7075 5350);
DISPLAY 0.872340 (-7075 5350);
PAINT AQUA (-7075 5350);
DISPLAY INVISIBLE (-7075 5350);
FORCEADD Q_CAP..1
(-7125 5075);
FORCEPROP 1 LAST LOCATION C78
J 0
(-7075 5175);
DISPLAY 0.978723 (-7075 5175);
FORCEPROP 0 LAST $SEC 1
J 0
(-7075 5225);
DISPLAY 0.680851 (-7075 5225);
PAINT MONO (-7075 5225);
DISPLAY INVISIBLE (-7075 5225);
FORCEPROP 0 LAST CDS_SEC 1
J 0
(-7075 5225);
DISPLAY 1.021277 (-7075 5225);
DISPLAY INVISIBLE (-7075 5225);
FORCEPROP 1 LASTPIN (-7125 5175) $PN 1
J 0
(-7115 5155);
DISPLAY 0.787234 (-7115 5155);
PAINT MONO (-7115 5155);
FORCEPROP 1 LASTPIN (-7125 4975) $PN 2
J 0
(-7115 4955);
DISPLAY 0.787234 (-7115 4955);
PAINT MONO (-7115 4955);
FORCEPROP 1 LAST MATERIAL X7R
J 0
(-7075 4975);
DISPLAY 0.510638 (-7075 4975);
FORCEPROP 1 LAST PACK_TYPE 0402
J 0
(-7075 4875);
DISPLAY 0.510638 (-7075 4875);
FORCEPROP 1 LAST TOLERANCE 10%
J 0
(-7075 5025);
DISPLAY 0.510638 (-7075 5025);
FORCEPROP 1 LAST VOLTAGE 25V
J 0
(-7075 5075);
DISPLAY 0.510638 (-7075 5075);
FORCEPROP 1 LAST VALUE 0.1UF
J 0
(-7075 5125);
DISPLAY 0.510638 (-7075 5125);
FORCEPROP 2 LAST CDS_LIB pure_quanta
J 0
(-7125 5075);
DISPLAY INVISIBLE (-7125 5075);
FORCEPROP 1 LAST PATH I18
J 0
(-7075 5225);
DISPLAY 0.978723 (-7075 5225);
PAINT WHITE (-7075 5225);
DISPLAY INVISIBLE (-7075 5225);
FORCEPROP 1 LAST PART_NUMBER CH4104K1B00
J 0
(-7075 4925);
DISPLAY 0.404255 (-7075 4925);
DISPLAY INVISIBLE (-7075 4925);
FORCEADD UNIVERSAL_GND..1
(-7150 5500);
FORCEPROP 3 LASTPIN (-7150 5550) SIG_NAME GND\g
J 0
(-7140 5560);
DISPLAY 0.659574 (-7140 5560);
PAINT MONO (-7140 5560);
DISPLAY INVISIBLE (-7140 5560);
FORCEPROP 2 LAST CDS_LIB pure_quanta_power
J 0
(-7150 5500);
DISPLAY INVISIBLE (-7150 5500);
FORCEPROP 1 LAST HDL_POWER GND
J 1
(-7125 5425);
DISPLAY 0.872340 (-7125 5425);
PAINT GREEN (-7125 5425);
DISPLAY INVISIBLE (-7125 5425);
FORCEPROP 1 LAST PATH I19
J 0
(-7075 5500);
DISPLAY 0.872340 (-7075 5500);
PAINT AQUA (-7075 5500);
DISPLAY INVISIBLE (-7075 5500);
FORCEADD Q_RES..2
(-6250 1375);
FORCEPROP 1 LAST LOCATION R4490
J 0
(-6205 1500);
DISPLAY 0.978723 (-6205 1500);
FORCEPROP 0 LAST $SEC 1
J 0
(-6200 1550);
DISPLAY 0.680851 (-6200 1550);
PAINT MONO (-6200 1550);
DISPLAY INVISIBLE (-6200 1550);
FORCEPROP 0 LAST CDS_SEC 1
J 0
(-6200 1550);
DISPLAY 1.021277 (-6200 1550);
DISPLAY INVISIBLE (-6200 1550);
FORCEPROP 1 LASTPIN (-6250 1475) $PN 1
J 0
(-6245 1437);
DISPLAY 0.787234 (-6245 1437);
PAINT MONO (-6245 1437);
FORCEPROP 1 LASTPIN (-6250 1275) $PN 2
J 0
(-6245 1285);
DISPLAY 0.787234 (-6245 1285);
PAINT MONO (-6245 1285);
FORCEPROP 1 LAST TOLERANCE 1%
J 0
(-6205 1400);
DISPLAY 0.638298 (-6205 1400);
FORCEPROP 1 LAST PACK_TYPE 0402LF
J 0
(-6210 1250);
DISPLAY 0.638298 (-6210 1250);
FORCEPROP 1 LAST MATERIAL EMPTY
J 0
(-6210 1300);
DISPLAY 0.638298 (-6210 1300);
PAINT RED (-6210 1300);
FORCEPROP 1 LAST WATTAGE 1/16W
J 0
(-6210 1350);
DISPLAY 0.638298 (-6210 1350);
FORCEPROP 1 LAST VALUE 4.75K
J 0
(-6205 1450);
DISPLAY 0.638298 (-6205 1450);
FORCEPROP 2 LAST CDS_LIB pure_quanta
J 0
(-6250 1375);
DISPLAY INVISIBLE (-6250 1375);
FORCEPROP 1 LAST PATH I2
J 0
(-6200 1550);
DISPLAY 0.978723 (-6200 1550);
PAINT WHITE (-6200 1550);
DISPLAY INVISIBLE (-6200 1550);
FORCEPROP 1 LAST PART_NUMBER CS24752FB03
J 0
(-6210 1250);
DISPLAY 0.638298 (-6210 1250);
DISPLAY INVISIBLE (-6210 1250);
FORCEADD Q_CAP..1
(-7150 5875);
FORCEPROP 1 LAST LOCATION C2334
J 0
(-7100 5975);
DISPLAY 0.978723 (-7100 5975);
FORCEPROP 0 LAST $SEC 1
J 0
(-7100 6025);
DISPLAY 0.680851 (-7100 6025);
PAINT MONO (-7100 6025);
DISPLAY INVISIBLE (-7100 6025);
FORCEPROP 0 LAST CDS_SEC 1
J 0
(-7100 6025);
DISPLAY 1.021277 (-7100 6025);
DISPLAY INVISIBLE (-7100 6025);
FORCEPROP 1 LASTPIN (-7150 5975) $PN 1
J 0
(-7140 5955);
DISPLAY 0.787234 (-7140 5955);
PAINT MONO (-7140 5955);
FORCEPROP 1 LASTPIN (-7150 5775) $PN 2
J 0
(-7140 5755);
DISPLAY 0.787234 (-7140 5755);
PAINT MONO (-7140 5755);
FORCEPROP 1 LAST MATERIAL X7R
J 0
(-7100 5775);
DISPLAY 0.510638 (-7100 5775);
FORCEPROP 1 LAST VOLTAGE 25V
J 0
(-7100 5875);
DISPLAY 0.510638 (-7100 5875);
FORCEPROP 1 LAST VALUE 0.1UF
J 0
(-7100 5925);
DISPLAY 0.510638 (-7100 5925);
FORCEPROP 1 LAST TOLERANCE 10%
J 0
(-7100 5825);
DISPLAY 0.510638 (-7100 5825);
FORCEPROP 1 LAST PACK_TYPE 0402
J 0
(-7100 5675);
DISPLAY 0.510638 (-7100 5675);
FORCEPROP 2 LAST CDS_LIB pure_quanta
J 0
(-7150 5875);
DISPLAY INVISIBLE (-7150 5875);
FORCEPROP 1 LAST PATH I20
J 0
(-7100 6025);
DISPLAY 0.978723 (-7100 6025);
PAINT WHITE (-7100 6025);
DISPLAY INVISIBLE (-7100 6025);
FORCEPROP 1 LAST PART_NUMBER CH4104K1B00
J 0
(-7100 5725);
DISPLAY 0.404255 (-7100 5725);
DISPLAY INVISIBLE (-7100 5725);
FORCEADD UNIVERSAL_POWER..1
(-6175 4300);
FORCEPROP 3 LASTPIN (-6175 4250) SIG_NAME P3V3_9ZXL045_P0_VDDR\g
J 0
(-6165 4260);
DISPLAY 0.659574 (-6165 4260);
PAINT MONO (-6165 4260);
DISPLAY INVISIBLE (-6165 4260);
FORCEPROP 1 LAST HDL_POWER P3V3_9ZXL045_P0_VDDR
J 1
(-6275 4350);
DISPLAY 0.872340 (-6275 4350);
PAINT SKYBLUE (-6275 4350);
FORCEPROP 2 LAST CDS_LIB pure_quanta_power
J 0
(-6175 4300);
DISPLAY INVISIBLE (-6175 4300);
FORCEPROP 1 LAST PATH I21
J 0
(-6125 4325);
DISPLAY 0.872340 (-6125 4325);
PAINT AQUA (-6125 4325);
DISPLAY INVISIBLE (-6125 4325);
FORCEADD UNIVERSAL_POWER..1
(-5775 4600);
FORCEPROP 3 LASTPIN (-5775 4550) SIG_NAME P3V3_9ZXL045_P0_VDD\g
J 0
(-5765 4560);
DISPLAY 0.659574 (-5765 4560);
PAINT MONO (-5765 4560);
DISPLAY INVISIBLE (-5765 4560);
FORCEPROP 1 LAST HDL_POWER P3V3_9ZXL045_P0_VDD
J 1
(-5775 4650);
DISPLAY 0.872340 (-5775 4650);
PAINT SKYBLUE (-5775 4650);
FORCEPROP 2 LAST CDS_LIB pure_quanta_power
J 0
(-5775 4600);
DISPLAY INVISIBLE (-5775 4600);
FORCEPROP 1 LAST PATH I22
J 0
(-5725 4625);
DISPLAY 0.872340 (-5725 4625);
PAINT AQUA (-5725 4625);
DISPLAY INVISIBLE (-5725 4625);
FORCEADD UNIVERSAL_POWER..1
(-5900 5850);
FORCEPROP 3 LASTPIN (-5900 5800) SIG_NAME P3V3_AUX\g
J 0
(-5890 5810);
DISPLAY 0.659574 (-5890 5810);
PAINT MONO (-5890 5810);
DISPLAY INVISIBLE (-5890 5810);
FORCEPROP 1 LAST HDL_POWER P3V3_AUX
J 1
(-5900 5900);
DISPLAY 0.872340 (-5900 5900);
PAINT YELLOW (-5900 5900);
FORCEPROP 2 LAST CDS_LIB pure_quanta_power
J 0
(-5900 5850);
DISPLAY INVISIBLE (-5900 5850);
FORCEPROP 1 LAST PATH I23
J 0
(-5850 5875);
DISPLAY 0.872340 (-5850 5875);
PAINT AQUA (-5850 5875);
DISPLAY INVISIBLE (-5850 5875);
FORCEADD Q_INDUCTOR..1
(-5450 5750);
FORCEPROP 1 LAST LOCATION L20
J 0
(-5575 5910);
DISPLAY 0.723404 (-5575 5910);
PAINT GREEN (-5575 5910);
FORCEPROP 0 LAST $SEC 1
J 0
(-5575 6050);
DISPLAY 0.680851 (-5575 6050);
PAINT MONO (-5575 6050);
DISPLAY INVISIBLE (-5575 6050);
FORCEPROP 0 LAST CDS_SEC 1
J 0
(-5575 6050);
DISPLAY 1.021277 (-5575 6050);
DISPLAY INVISIBLE (-5575 6050);
FORCEPROP 0 LASTPIN (-5550 5725) $PN 1
J 2
(-5560 5735);
DISPLAY 0.680851 (-5560 5735);
PAINT MONO (-5560 5735);
FORCEPROP 0 LASTPIN (-5350 5725) $PN 2
J 0
(-5340 5735);
DISPLAY 0.680851 (-5340 5735);
PAINT MONO (-5340 5735);
FORCEPROP 1 LAST MATERIAL IND
J 0
(-5575 5805);
DISPLAY 0.723404 (-5575 5805);
PAINT GREEN (-5575 5805);
FORCEPROP 2 LAST PACK_TYPE SMLF
J 0
(-5575 6000);
DISPLAY 0.638298 (-5575 6000);
FORCEPROP 2 LAST VALUE FCM2012KF-601T/0.5A
J 0
(-5575 5950);
DISPLAY 0.638298 (-5575 5950);
FORCEPROP 1 LAST NEEDS_NO_SIZE TRUE
J 0
(-5450 5750);
DISPLAY 0.468085 (-5450 5750);
PAINT GREEN (-5450 5750);
DISPLAY INVISIBLE (-5450 5750);
FORCEPROP 2 LAST CDS_LIB pure_quanta
J 0
(-5450 5750);
DISPLAY INVISIBLE (-5450 5750);
FORCEPROP 1 LAST PATH I24
J 0
(-5375 5805);
DISPLAY 0.723404 (-5375 5805);
PAINT GREEN (-5375 5805);
DISPLAY INVISIBLE (-5375 5805);
FORCEPROP 1 LAST PART_NUMBER CX601T05003
J 0
(-5575 5860);
DISPLAY 0.723404 (-5575 5860);
PAINT GREEN (-5575 5860);
DISPLAY INVISIBLE (-5575 5860);
FORCEADD UNIVERSAL_POWER..1
(-9200 6150);
FORCEPROP 3 LASTPIN (-9200 6100) SIG_NAME P3V3_AUX\g
J 0
(-9190 6110);
DISPLAY 0.659574 (-9190 6110);
PAINT MONO (-9190 6110);
DISPLAY INVISIBLE (-9190 6110);
FORCEPROP 1 LAST HDL_POWER P3V3_AUX
J 1
(-9200 6200);
DISPLAY 0.872340 (-9200 6200);
PAINT YELLOW (-9200 6200);
FORCEPROP 2 LAST CDS_LIB pure_quanta_power
J 0
(-9200 6150);
DISPLAY INVISIBLE (-9200 6150);
FORCEPROP 1 LAST PATH I25
J 0
(-9150 6175);
DISPLAY 0.872340 (-9150 6175);
PAINT AQUA (-9150 6175);
DISPLAY INVISIBLE (-9150 6175);
FORCEADD Q_INDUCTOR..1
(-8775 6075);
FORCEPROP 1 LAST LOCATION L19
J 0
(-8900 6235);
DISPLAY 0.723404 (-8900 6235);
PAINT GREEN (-8900 6235);
FORCEPROP 0 LAST $SEC 1
J 0
(-8900 6375);
DISPLAY 0.680851 (-8900 6375);
PAINT MONO (-8900 6375);
DISPLAY INVISIBLE (-8900 6375);
FORCEPROP 0 LAST CDS_SEC 1
J 0
(-8900 6375);
DISPLAY 1.021277 (-8900 6375);
DISPLAY INVISIBLE (-8900 6375);
FORCEPROP 0 LASTPIN (-8875 6050) $PN 1
J 2
(-8885 6060);
DISPLAY 0.680851 (-8885 6060);
PAINT MONO (-8885 6060);
FORCEPROP 0 LASTPIN (-8675 6050) $PN 2
J 0
(-8665 6060);
DISPLAY 0.680851 (-8665 6060);
PAINT MONO (-8665 6060);
FORCEPROP 1 LAST MATERIAL IND
J 0
(-8900 6130);
DISPLAY 0.723404 (-8900 6130);
PAINT GREEN (-8900 6130);
FORCEPROP 2 LAST PACK_TYPE SMLF
J 0
(-8900 6325);
DISPLAY 0.638298 (-8900 6325);
FORCEPROP 2 LAST VALUE FCM2012KF-601T/0.5A
J 0
(-8900 6275);
DISPLAY 0.638298 (-8900 6275);
FORCEPROP 2 LAST CDS_LIB pure_quanta
J 0
(-8775 6075);
DISPLAY INVISIBLE (-8775 6075);
FORCEPROP 1 LAST NEEDS_NO_SIZE TRUE
J 0
(-8775 6075);
DISPLAY 0.468085 (-8775 6075);
PAINT GREEN (-8775 6075);
DISPLAY INVISIBLE (-8775 6075);
FORCEPROP 1 LAST PATH I26
J 0
(-8700 6130);
DISPLAY 0.723404 (-8700 6130);
PAINT GREEN (-8700 6130);
DISPLAY INVISIBLE (-8700 6130);
FORCEPROP 1 LAST PART_NUMBER CX601T05003
J 0
(-8900 6185);
DISPLAY 0.723404 (-8900 6185);
PAINT GREEN (-8900 6185);
DISPLAY INVISIBLE (-8900 6185);
FORCEADD Q_RES..1
(-7925 6050);
FORCEPROP 1 LAST LOCATION R4493
J 0
(-8125 6050);
DISPLAY 0.638298 (-8125 6050);
FORCEPROP 0 LAST SEC 1
J 0
(-7750 6200);
DISPLAY 0.680851 (-7750 6200);
PAINT MONO (-7750 6200);
DISPLAY INVISIBLE (-7750 6200);
FORCEPROP 1 LASTPIN (-8025 6050) $PN 1
J 0
(-8013 6062);
DISPLAY 0.787234 (-8013 6062);
PAINT MONO (-8013 6062);
FORCEPROP 1 LASTPIN (-7825 6050) $PN 2
J 0
(-7863 6062);
DISPLAY 0.787234 (-7863 6062);
PAINT MONO (-7863 6062);
FORCEPROP 1 LAST MATERIAL CHIP
J 0
(-7600 6050);
DISPLAY 0.638298 (-7600 6050);
FORCEPROP 1 LAST PACK_TYPE 0603LF
J 0
(-8075 6175);
DISPLAY 0.510638 (-8075 6175);
FORCEPROP 1 LAST TOLERANCE 1%
J 0
(-7700 6050);
DISPLAY 0.638298 (-7700 6050);
FORCEPROP 1 LAST VALUE 1
J 2
(-7725 6050);
DISPLAY 0.638298 (-7725 6050);
FORCEPROP 1 LAST WATTAGE 1/10W
J 2
(-7750 6175);
DISPLAY 0.510638 (-7750 6175);
FORCEPROP 2 LAST SEC_TYPE 0603LF
J 0
(-7975 6250);
DISPLAY 0.680851 (-7975 6250);
DISPLAY INVISIBLE (-7975 6250);
FORCEPROP 2 LAST CDS_LIB pure_quanta
J 0
(-7925 6050);
DISPLAY INVISIBLE (-7925 6050);
FORCEPROP 1 LAST PATH I27
J 0
(-7975 6200);
DISPLAY 0.978723 (-7975 6200);
PAINT WHITE (-7975 6200);
DISPLAY INVISIBLE (-7975 6200);
FORCEPROP 1 LAST PART_NUMBER CS-1003F900
J 0
(-8075 6125);
DISPLAY 0.510638 (-8075 6125);
DISPLAY INVISIBLE (-8075 6125);
FORCEADD UNIVERSAL_POWER..1
(-7150 6125);
FORCEPROP 3 LASTPIN (-7150 6075) SIG_NAME P3V3_9ZXL045_P0_VDDA\g
J 0
(-7140 6085);
DISPLAY 0.659574 (-7140 6085);
PAINT MONO (-7140 6085);
DISPLAY INVISIBLE (-7140 6085);
FORCEPROP 1 LAST HDL_POWER P3V3_9ZXL045_P0_VDDA
J 1
(-7150 6175);
DISPLAY 0.872340 (-7150 6175);
PAINT SKYBLUE (-7150 6175);
FORCEPROP 2 LAST CDS_LIB pure_quanta_power
J 0
(-7150 6125);
DISPLAY INVISIBLE (-7150 6125);
FORCEPROP 1 LAST PATH I28
J 0
(-7100 6150);
DISPLAY 0.872340 (-7100 6150);
PAINT AQUA (-7100 6150);
DISPLAY INVISIBLE (-7100 6150);
FORCEADD Q_RES..2
(-4250 1325);
FORCEPROP 1 LAST LOCATION R4492
J 0
(-4205 1450);
DISPLAY 0.978723 (-4205 1450);
FORCEPROP 0 LAST $SEC 1
J 0
(-4200 1500);
DISPLAY 0.680851 (-4200 1500);
PAINT MONO (-4200 1500);
DISPLAY INVISIBLE (-4200 1500);
FORCEPROP 0 LAST CDS_SEC 1
J 0
(-4200 1500);
DISPLAY 1.021277 (-4200 1500);
DISPLAY INVISIBLE (-4200 1500);
FORCEPROP 1 LASTPIN (-4250 1425) $PN 1
J 0
(-4245 1387);
DISPLAY 0.787234 (-4245 1387);
PAINT MONO (-4245 1387);
FORCEPROP 1 LASTPIN (-4250 1225) $PN 2
J 0
(-4245 1235);
DISPLAY 0.787234 (-4245 1235);
PAINT MONO (-4245 1235);
FORCEPROP 1 LAST TOLERANCE 1%
J 0
(-4205 1350);
DISPLAY 0.638298 (-4205 1350);
FORCEPROP 1 LAST PACK_TYPE 0402LF
J 0
(-4210 1200);
DISPLAY 0.638298 (-4210 1200);
FORCEPROP 1 LAST VALUE 10K
J 0
(-4205 1400);
DISPLAY 0.638298 (-4205 1400);
FORCEPROP 1 LAST WATTAGE 1/16W
J 0
(-4210 1300);
DISPLAY 0.638298 (-4210 1300);
FORCEPROP 1 LAST MATERIAL CHIP
J 0
(-4225 1250);
DISPLAY 0.638298 (-4225 1250);
FORCEPROP 2 LAST CDS_LIB pure_quanta
J 0
(-4250 1325);
DISPLAY INVISIBLE (-4250 1325);
FORCEPROP 1 LAST PATH I29
J 0
(-4200 1500);
DISPLAY 0.978723 (-4200 1500);
PAINT WHITE (-4200 1500);
DISPLAY INVISIBLE (-4200 1500);
FORCEPROP 1 LAST PART_NUMBER CS31002FB08
J 0
(-4210 1200);
DISPLAY 0.638298 (-4210 1200);
DISPLAY INVISIBLE (-4210 1200);
FORCEADD Q_RES..2
(-6250 1800);
FORCEPROP 1 LAST LOCATION R4489
J 0
(-6205 1925);
DISPLAY 0.978723 (-6205 1925);
FORCEPROP 0 LAST $SEC 1
J 0
(-6200 1975);
DISPLAY 0.680851 (-6200 1975);
PAINT MONO (-6200 1975);
DISPLAY INVISIBLE (-6200 1975);
FORCEPROP 0 LAST CDS_SEC 1
J 0
(-6200 1975);
DISPLAY 1.021277 (-6200 1975);
DISPLAY INVISIBLE (-6200 1975);
FORCEPROP 1 LASTPIN (-6250 1900) $PN 1
J 0
(-6245 1862);
DISPLAY 0.787234 (-6245 1862);
PAINT MONO (-6245 1862);
FORCEPROP 1 LASTPIN (-6250 1700) $PN 2
J 0
(-6245 1710);
DISPLAY 0.787234 (-6245 1710);
PAINT MONO (-6245 1710);
FORCEPROP 1 LAST MATERIAL CHIP
J 0
(-6210 1725);
DISPLAY 0.638298 (-6210 1725);
FORCEPROP 1 LAST PACK_TYPE 0402LF
J 0
(-6210 1675);
DISPLAY 0.638298 (-6210 1675);
FORCEPROP 1 LAST VALUE 4.75K
J 0
(-6205 1875);
DISPLAY 0.638298 (-6205 1875);
FORCEPROP 1 LAST TOLERANCE 1%
J 0
(-6205 1825);
DISPLAY 0.638298 (-6205 1825);
FORCEPROP 1 LAST WATTAGE 1/16W
J 0
(-6210 1775);
DISPLAY 0.638298 (-6210 1775);
FORCEPROP 2 LAST CDS_LIB pure_quanta
J 0
(-6250 1800);
DISPLAY INVISIBLE (-6250 1800);
FORCEPROP 1 LAST PATH I3
J 0
(-6200 1975);
DISPLAY 0.978723 (-6200 1975);
PAINT WHITE (-6200 1975);
DISPLAY INVISIBLE (-6200 1975);
FORCEPROP 1 LAST PART_NUMBER CS24752FB03
J 0
(-6210 1675);
DISPLAY 0.638298 (-6210 1675);
DISPLAY INVISIBLE (-6210 1675);
FORCEADD UNIVERSAL_GND..1
(-4250 1075);
FORCEPROP 3 LASTPIN (-4250 1125) SIG_NAME GND\g
J 0
(-4240 1135);
DISPLAY 0.659574 (-4240 1135);
PAINT MONO (-4240 1135);
DISPLAY INVISIBLE (-4240 1135);
FORCEPROP 2 LAST CDS_LIB pure_quanta_power
J 0
(-4250 1075);
DISPLAY INVISIBLE (-4250 1075);
FORCEPROP 1 LAST HDL_POWER GND
J 1
(-4225 1000);
DISPLAY 0.872340 (-4225 1000);
PAINT GREEN (-4225 1000);
DISPLAY INVISIBLE (-4225 1000);
FORCEPROP 1 LAST PATH I30
J 0
(-4175 1075);
DISPLAY 0.872340 (-4175 1075);
PAINT AQUA (-4175 1075);
DISPLAY INVISIBLE (-4175 1075);
FORCEADD Q_RES..2
(-4250 1800);
FORCEPROP 1 LAST LOCATION R4491
J 0
(-4205 1925);
DISPLAY 0.978723 (-4205 1925);
FORCEPROP 0 LAST $SEC 1
J 0
(-4200 1975);
DISPLAY 0.680851 (-4200 1975);
PAINT MONO (-4200 1975);
DISPLAY INVISIBLE (-4200 1975);
FORCEPROP 0 LAST CDS_SEC 1
J 0
(-4200 1975);
DISPLAY 1.021277 (-4200 1975);
DISPLAY INVISIBLE (-4200 1975);
FORCEPROP 1 LASTPIN (-4250 1900) $PN 1
J 0
(-4245 1862);
DISPLAY 0.787234 (-4245 1862);
PAINT MONO (-4245 1862);
FORCEPROP 1 LASTPIN (-4250 1700) $PN 2
J 0
(-4245 1710);
DISPLAY 0.787234 (-4245 1710);
PAINT MONO (-4245 1710);
FORCEPROP 1 LAST WATTAGE 1/16W
J 0
(-4210 1775);
DISPLAY 0.638298 (-4210 1775);
FORCEPROP 1 LAST MATERIAL CHIP
J 0
(-4225 1725);
DISPLAY 0.638298 (-4225 1725);
FORCEPROP 1 LAST TOLERANCE 1%
J 0
(-4205 1825);
DISPLAY 0.638298 (-4205 1825);
FORCEPROP 1 LAST VALUE 10K
J 0
(-4205 1875);
DISPLAY 0.638298 (-4205 1875);
FORCEPROP 1 LAST PACK_TYPE 0402LF
J 0
(-4210 1675);
DISPLAY 0.638298 (-4210 1675);
FORCEPROP 2 LAST CDS_LIB pure_quanta
J 0
(-4250 1800);
DISPLAY INVISIBLE (-4250 1800);
FORCEPROP 1 LAST PATH I31
J 0
(-4200 1975);
DISPLAY 0.978723 (-4200 1975);
PAINT WHITE (-4200 1975);
DISPLAY INVISIBLE (-4200 1975);
FORCEPROP 1 LAST PART_NUMBER CS31002FB08
J 0
(-4210 1675);
DISPLAY 0.638298 (-4210 1675);
DISPLAY INVISIBLE (-4210 1675);
FORCEADD OFFPAGE..2
(-3525 1575);
FORCEPROP 2 LAST $XR0 182 
J 0
(-3336 1575);
DISPLAY 0.638298 (-3336 1575);
PAINT MONO (-3336 1575);
FORCEPROP 2 LAST CDS_LIB standard
J 0
(-3525 1575);
DISPLAY INVISIBLE (-3525 1575);
FORCEPROP 1 LAST OFFPAGE TRUE
J 0
(-3200 1450);
DISPLAY 0.872340 (-3200 1450);
DISPLAY INVISIBLE (-3200 1450);
FORCEPROP 1 LAST COMMENT_BODY TRUE
J 0
(-3570 1480);
DISPLAY 0.872340 (-3570 1480);
PAINT GREEN (-3570 1480);
DISPLAY INVISIBLE (-3570 1480);
FORCEPROP 2 LAST PATH I32
J 0
(-3325 1625);
DISPLAY 0.680851 (-3325 1625);
DISPLAY INVISIBLE (-3325 1625);
FORCEADD UNIVERSAL_POWER..1
(-4250 2100);
FORCEPROP 3 LASTPIN (-4250 2050) SIG_NAME P3V3_AUX\g
J 0
(-4240 2060);
DISPLAY 0.659574 (-4240 2060);
PAINT MONO (-4240 2060);
DISPLAY INVISIBLE (-4240 2060);
FORCEPROP 1 LAST HDL_POWER P3V3_AUX
J 1
(-4250 2150);
DISPLAY 0.872340 (-4250 2150);
PAINT YELLOW (-4250 2150);
FORCEPROP 2 LAST CDS_LIB pure_quanta_power
J 0
(-4250 2100);
DISPLAY INVISIBLE (-4250 2100);
FORCEPROP 1 LAST PATH I33
J 0
(-4200 2125);
DISPLAY 0.872340 (-4200 2125);
PAINT AQUA (-4200 2125);
DISPLAY INVISIBLE (-4200 2125);
FORCEADD UNIVERSAL_GND..1
(-4025 2775);
FORCEPROP 3 LASTPIN (-4025 2825) SIG_NAME GND\g
J 0
(-4015 2835);
DISPLAY 0.659574 (-4015 2835);
PAINT MONO (-4015 2835);
DISPLAY INVISIBLE (-4015 2835);
FORCEPROP 2 LAST CDS_LIB pure_quanta_power
J 0
(-4025 2775);
DISPLAY INVISIBLE (-4025 2775);
FORCEPROP 1 LAST HDL_POWER GND
J 1
(-4000 2700);
DISPLAY 0.872340 (-4000 2700);
PAINT GREEN (-4000 2700);
DISPLAY INVISIBLE (-4000 2700);
FORCEPROP 1 LAST PATH I34
J 0
(-3950 2775);
DISPLAY 0.872340 (-3950 2775);
PAINT AQUA (-3950 2775);
DISPLAY INVISIBLE (-3950 2775);
FORCEADD OFFPAGE..2
(-5525 1575);
FORCEPROP 2 LAST $XR0 182 
J 0
(-5336 1575);
DISPLAY 0.638298 (-5336 1575);
PAINT MONO (-5336 1575);
FORCEPROP 2 LAST CDS_LIB standard
J 0
(-5525 1575);
DISPLAY INVISIBLE (-5525 1575);
FORCEPROP 1 LAST OFFPAGE TRUE
J 0
(-5200 1450);
DISPLAY 0.872340 (-5200 1450);
DISPLAY INVISIBLE (-5200 1450);
FORCEPROP 1 LAST COMMENT_BODY TRUE
J 0
(-5570 1480);
DISPLAY 0.872340 (-5570 1480);
PAINT GREEN (-5570 1480);
DISPLAY INVISIBLE (-5570 1480);
FORCEPROP 2 LAST PATH I4
J 0
(-5325 1625);
DISPLAY 0.680851 (-5325 1625);
DISPLAY INVISIBLE (-5325 1625);
FORCEADD Q_CAP..1
(-4575 5525);
FORCEPROP 1 LAST LOCATION C2329
J 0
(-4525 5625);
DISPLAY 0.978723 (-4525 5625);
FORCEPROP 0 LAST $SEC 1
J 0
(-4525 5675);
DISPLAY 0.680851 (-4525 5675);
PAINT MONO (-4525 5675);
DISPLAY INVISIBLE (-4525 5675);
FORCEPROP 0 LAST CDS_SEC 1
J 0
(-4525 5675);
DISPLAY 1.021277 (-4525 5675);
DISPLAY INVISIBLE (-4525 5675);
FORCEPROP 1 LASTPIN (-4575 5625) $PN 1
J 0
(-4565 5605);
DISPLAY 0.787234 (-4565 5605);
PAINT MONO (-4565 5605);
FORCEPROP 1 LASTPIN (-4575 5425) $PN 2
J 0
(-4565 5405);
DISPLAY 0.787234 (-4565 5405);
PAINT MONO (-4565 5405);
FORCEPROP 1 LAST PACK_TYPE 0402
J 0
(-4525 5325);
DISPLAY 0.510638 (-4525 5325);
FORCEPROP 1 LAST MATERIAL X7R
J 0
(-4525 5425);
DISPLAY 0.510638 (-4525 5425);
FORCEPROP 1 LAST TOLERANCE 10%
J 0
(-4525 5475);
DISPLAY 0.510638 (-4525 5475);
FORCEPROP 1 LAST VALUE 0.1UF
J 0
(-4525 5575);
DISPLAY 0.510638 (-4525 5575);
FORCEPROP 1 LAST VOLTAGE 25V
J 0
(-4525 5525);
DISPLAY 0.510638 (-4525 5525);
FORCEPROP 2 LAST CDS_LIB pure_quanta
J 0
(-4575 5525);
DISPLAY INVISIBLE (-4575 5525);
FORCEPROP 1 LAST PATH I40
J 0
(-4525 5675);
DISPLAY 0.978723 (-4525 5675);
PAINT WHITE (-4525 5675);
DISPLAY INVISIBLE (-4525 5675);
FORCEPROP 1 LAST PART_NUMBER CH4104K1B00
J 0
(-4525 5375);
DISPLAY 0.404255 (-4525 5375);
DISPLAY INVISIBLE (-4525 5375);
FORCEADD Q_CAP..1
(-4325 5525);
FORCEPROP 1 LAST LOCATION C79
J 0
(-4275 5625);
DISPLAY 0.978723 (-4275 5625);
FORCEPROP 0 LAST $SEC 1
J 0
(-4275 5675);
DISPLAY 0.680851 (-4275 5675);
PAINT MONO (-4275 5675);
DISPLAY INVISIBLE (-4275 5675);
FORCEPROP 0 LAST CDS_SEC 1
J 0
(-4275 5675);
DISPLAY 1.021277 (-4275 5675);
DISPLAY INVISIBLE (-4275 5675);
FORCEPROP 1 LASTPIN (-4325 5625) $PN 1
J 0
(-4315 5605);
DISPLAY 0.787234 (-4315 5605);
PAINT MONO (-4315 5605);
FORCEPROP 1 LASTPIN (-4325 5425) $PN 2
J 0
(-4315 5405);
DISPLAY 0.787234 (-4315 5405);
PAINT MONO (-4315 5405);
FORCEPROP 1 LAST VOLTAGE 25V
J 0
(-4275 5525);
DISPLAY 0.510638 (-4275 5525);
FORCEPROP 1 LAST TOLERANCE 10%
J 0
(-4275 5475);
DISPLAY 0.510638 (-4275 5475);
FORCEPROP 1 LAST PACK_TYPE 0402
J 0
(-4275 5325);
DISPLAY 0.510638 (-4275 5325);
FORCEPROP 1 LAST VALUE 0.1UF
J 0
(-4275 5575);
DISPLAY 0.510638 (-4275 5575);
FORCEPROP 1 LAST MATERIAL X7R
J 0
(-4275 5425);
DISPLAY 0.510638 (-4275 5425);
FORCEPROP 2 LAST CDS_LIB pure_quanta
J 0
(-4325 5525);
DISPLAY INVISIBLE (-4325 5525);
FORCEPROP 1 LAST PATH I41
J 0
(-4275 5675);
DISPLAY 0.978723 (-4275 5675);
PAINT WHITE (-4275 5675);
DISPLAY INVISIBLE (-4275 5675);
FORCEPROP 1 LAST PART_NUMBER CH4104K1B00
J 0
(-4275 5375);
DISPLAY 0.404255 (-4275 5375);
DISPLAY INVISIBLE (-4275 5375);
FORCEADD UNIVERSAL_POWER..1
(-3900 4600);
FORCEPROP 3 LASTPIN (-3900 4550) SIG_NAME P3V3_9ZXL045_P0_VDDA\g
J 0
(-3890 4560);
DISPLAY 0.659574 (-3890 4560);
PAINT MONO (-3890 4560);
DISPLAY INVISIBLE (-3890 4560);
FORCEPROP 1 LAST HDL_POWER P3V3_9ZXL045_P0_VDDA
J 1
(-3900 4650);
DISPLAY 0.872340 (-3900 4650);
PAINT SKYBLUE (-3900 4650);
FORCEPROP 2 LAST CDS_LIB pure_quanta_power
J 0
(-3900 4600);
DISPLAY INVISIBLE (-3900 4600);
FORCEPROP 1 LAST PATH I42
J 0
(-3850 4625);
DISPLAY 0.872340 (-3850 4625);
PAINT AQUA (-3850 4625);
DISPLAY INVISIBLE (-3850 4625);
FORCEADD OFFPAGE..1
R 2
(-3500 4175);
FORCEPROP 2 LAST $XR0 182 
J 0
(-3314 4175);
DISPLAY 0.638298 (-3314 4175);
PAINT MONO (-3314 4175);
FORCEPROP 2 LAST CDS_LIB standard
J 2
(-3500 4175);
DISPLAY INVISIBLE (-3500 4175);
FORCEPROP 1 LAST OFFPAGE TRUE
J 2
(-3825 4050);
DISPLAY 1.170213 (-3825 4050);
PAINT GREEN (-3825 4050);
DISPLAY INVISIBLE (-3825 4050);
FORCEPROP 1 LAST COMMENT_BODY TRUE
J 2
(-3625 4075);
DISPLAY 1.170213 (-3625 4075);
PAINT GREEN (-3625 4075);
DISPLAY INVISIBLE (-3625 4075);
FORCEPROP 2 LAST PATH I43
J 0
(-3300 4225);
DISPLAY 0.680851 (-3300 4225);
DISPLAY INVISIBLE (-3300 4225);
FORCEADD Q_CAP..1
(-4075 5525);
FORCEPROP 1 LAST LOCATION C80
J 0
(-4025 5625);
DISPLAY 0.978723 (-4025 5625);
FORCEPROP 0 LAST $SEC 1
J 0
(-4025 5675);
DISPLAY 0.680851 (-4025 5675);
PAINT MONO (-4025 5675);
DISPLAY INVISIBLE (-4025 5675);
FORCEPROP 0 LAST CDS_SEC 1
J 0
(-4025 5675);
DISPLAY 1.021277 (-4025 5675);
DISPLAY INVISIBLE (-4025 5675);
FORCEPROP 1 LASTPIN (-4075 5625) $PN 1
J 0
(-4065 5605);
DISPLAY 0.787234 (-4065 5605);
PAINT MONO (-4065 5605);
FORCEPROP 1 LASTPIN (-4075 5425) $PN 2
J 0
(-4065 5405);
DISPLAY 0.787234 (-4065 5405);
PAINT MONO (-4065 5405);
FORCEPROP 1 LAST VALUE 0.1UF
J 0
(-4025 5575);
DISPLAY 0.510638 (-4025 5575);
FORCEPROP 1 LAST PACK_TYPE 0402
J 0
(-4025 5325);
DISPLAY 0.510638 (-4025 5325);
FORCEPROP 1 LAST TOLERANCE 10%
J 0
(-4025 5475);
DISPLAY 0.510638 (-4025 5475);
FORCEPROP 1 LAST VOLTAGE 25V
J 0
(-4025 5525);
DISPLAY 0.510638 (-4025 5525);
FORCEPROP 1 LAST MATERIAL X7R
J 0
(-4025 5425);
DISPLAY 0.510638 (-4025 5425);
FORCEPROP 2 LAST CDS_LIB pure_quanta
J 0
(-4075 5525);
DISPLAY INVISIBLE (-4075 5525);
FORCEPROP 1 LAST PATH I44
J 0
(-4025 5675);
DISPLAY 0.978723 (-4025 5675);
PAINT WHITE (-4025 5675);
DISPLAY INVISIBLE (-4025 5675);
FORCEPROP 1 LAST PART_NUMBER CH4104K1B00
J 0
(-4025 5375);
DISPLAY 0.404255 (-4025 5375);
DISPLAY INVISIBLE (-4025 5375);
FORCEADD Q_CAP..1
(-3825 5525);
FORCEPROP 1 LAST LOCATION C81
J 0
(-3775 5625);
DISPLAY 0.978723 (-3775 5625);
FORCEPROP 0 LAST $SEC 1
J 0
(-3775 5675);
DISPLAY 0.680851 (-3775 5675);
PAINT MONO (-3775 5675);
DISPLAY INVISIBLE (-3775 5675);
FORCEPROP 0 LAST CDS_SEC 1
J 0
(-3775 5675);
DISPLAY 1.021277 (-3775 5675);
DISPLAY INVISIBLE (-3775 5675);
FORCEPROP 1 LASTPIN (-3825 5625) $PN 1
J 0
(-3815 5605);
DISPLAY 0.787234 (-3815 5605);
PAINT MONO (-3815 5605);
FORCEPROP 1 LASTPIN (-3825 5425) $PN 2
J 0
(-3815 5405);
DISPLAY 0.787234 (-3815 5405);
PAINT MONO (-3815 5405);
FORCEPROP 1 LAST VOLTAGE 25V
J 0
(-3775 5525);
DISPLAY 0.510638 (-3775 5525);
FORCEPROP 1 LAST PACK_TYPE 0402
J 0
(-3775 5325);
DISPLAY 0.510638 (-3775 5325);
FORCEPROP 1 LAST VALUE 0.1UF
J 0
(-3775 5575);
DISPLAY 0.510638 (-3775 5575);
FORCEPROP 1 LAST TOLERANCE 10%
J 0
(-3775 5475);
DISPLAY 0.510638 (-3775 5475);
FORCEPROP 1 LAST MATERIAL X7R
J 0
(-3775 5425);
DISPLAY 0.510638 (-3775 5425);
FORCEPROP 2 LAST CDS_LIB pure_quanta
J 0
(-3825 5525);
DISPLAY INVISIBLE (-3825 5525);
FORCEPROP 1 LAST PATH I45
J 0
(-3775 5675);
DISPLAY 0.978723 (-3775 5675);
PAINT WHITE (-3775 5675);
DISPLAY INVISIBLE (-3775 5675);
FORCEPROP 1 LAST PART_NUMBER CH4104K1B00
J 0
(-3775 5375);
DISPLAY 0.404255 (-3775 5375);
DISPLAY INVISIBLE (-3775 5375);
FORCEADD UNIVERSAL_GND..1
(-3550 5175);
FORCEPROP 3 LASTPIN (-3550 5225) SIG_NAME GND\g
J 0
(-3540 5235);
DISPLAY 0.659574 (-3540 5235);
PAINT MONO (-3540 5235);
DISPLAY INVISIBLE (-3540 5235);
FORCEPROP 2 LAST CDS_LIB pure_quanta_power
J 0
(-3550 5175);
DISPLAY INVISIBLE (-3550 5175);
FORCEPROP 1 LAST HDL_POWER GND
J 1
(-3525 5100);
DISPLAY 0.872340 (-3525 5100);
PAINT GREEN (-3525 5100);
DISPLAY INVISIBLE (-3525 5100);
FORCEPROP 1 LAST PATH I46
J 0
(-3475 5175);
DISPLAY 0.872340 (-3475 5175);
PAINT AQUA (-3475 5175);
DISPLAY INVISIBLE (-3475 5175);
FORCEADD Q_CAP..1
(-3550 5525);
FORCEPROP 1 LAST LOCATION C2339
J 0
(-3500 5625);
DISPLAY 0.978723 (-3500 5625);
FORCEPROP 2 LAST $SEC 1
J 0
(-3500 5725);
DISPLAY 0.680851 (-3500 5725);
PAINT MONO (-3500 5725);
DISPLAY INVISIBLE (-3500 5725);
FORCEPROP 2 LAST CDS_SEC 1
J 0
(-3500 5725);
DISPLAY 1.021277 (-3500 5725);
DISPLAY INVISIBLE (-3500 5725);
FORCEPROP 1 LASTPIN (-3550 5625) $PN 1
J 0
(-3540 5605);
DISPLAY 0.787234 (-3540 5605);
PAINT MONO (-3540 5605);
FORCEPROP 1 LASTPIN (-3550 5425) $PN 2
J 0
(-3540 5405);
DISPLAY 0.787234 (-3540 5405);
PAINT MONO (-3540 5405);
FORCEPROP 1 LAST VOLTAGE 25V
J 0
(-3500 5525);
DISPLAY 0.510638 (-3500 5525);
FORCEPROP 1 LAST VALUE 0.1UF
J 0
(-3500 5575);
DISPLAY 0.510638 (-3500 5575);
FORCEPROP 1 LAST PACK_TYPE 0402
J 0
(-3500 5325);
DISPLAY 0.510638 (-3500 5325);
FORCEPROP 1 LAST MATERIAL X7R
J 0
(-3500 5425);
DISPLAY 0.510638 (-3500 5425);
FORCEPROP 1 LAST TOLERANCE 10%
J 0
(-3500 5475);
DISPLAY 0.510638 (-3500 5475);
FORCEPROP 2 LAST CDS_LIB pure_quanta
J 0
(-3550 5525);
DISPLAY INVISIBLE (-3550 5525);
FORCEPROP 1 LAST PATH I47
J 0
(-3500 5675);
DISPLAY 0.978723 (-3500 5675);
PAINT WHITE (-3500 5675);
DISPLAY INVISIBLE (-3500 5675);
FORCEPROP 1 LAST PART_NUMBER CH4104K1B00
J 0
(-3500 5375);
DISPLAY 0.404255 (-3500 5375);
DISPLAY INVISIBLE (-3500 5375);
FORCEADD UNIVERSAL_POWER..1
(-3550 5875);
FORCEPROP 3 LASTPIN (-3550 5825) SIG_NAME P3V3_9ZXL045_P0_VDD\g
J 0
(-3540 5835);
DISPLAY 0.659574 (-3540 5835);
PAINT MONO (-3540 5835);
DISPLAY INVISIBLE (-3540 5835);
FORCEPROP 1 LAST HDL_POWER P3V3_9ZXL045_P0_VDD
J 1
(-3550 5925);
DISPLAY 0.872340 (-3550 5925);
PAINT SKYBLUE (-3550 5925);
FORCEPROP 2 LAST CDS_LIB pure_quanta_power
J 0
(-3550 5875);
DISPLAY INVISIBLE (-3550 5875);
FORCEPROP 1 LAST PATH I48
J 0
(-3500 5900);
DISPLAY 0.872340 (-3500 5900);
PAINT AQUA (-3500 5900);
DISPLAY INVISIBLE (-3500 5900);
FORCEADD OFFPAGE..2
(-2850 3725);
FORCEPROP 2 LAST $XR0 299 
J 0
(-2661 3725);
DISPLAY 0.638298 (-2661 3725);
PAINT MONO (-2661 3725);
FORCEPROP 2 LAST CDS_LIB standard
J 0
(-2850 3725);
DISPLAY INVISIBLE (-2850 3725);
FORCEPROP 1 LAST OFFPAGE TRUE
J 0
(-2525 3600);
DISPLAY 0.872340 (-2525 3600);
PAINT GREEN (-2525 3600);
DISPLAY INVISIBLE (-2525 3600);
FORCEPROP 1 LAST COMMENT_BODY TRUE
J 0
(-2895 3630);
DISPLAY 0.872340 (-2895 3630);
PAINT GREEN (-2895 3630);
DISPLAY INVISIBLE (-2895 3630);
FORCEPROP 2 LAST PATH I49
J 0
(-2650 3775);
DISPLAY 0.680851 (-2650 3775);
DISPLAY INVISIBLE (-2650 3775);
FORCEADD OFFPAGE..2
(-2850 3775);
FORCEPROP 2 LAST $XR0 299 
J 0
(-2661 3775);
DISPLAY 0.638298 (-2661 3775);
PAINT MONO (-2661 3775);
FORCEPROP 2 LAST CDS_LIB standard
J 0
(-2850 3775);
DISPLAY INVISIBLE (-2850 3775);
FORCEPROP 1 LAST OFFPAGE TRUE
J 0
(-2525 3650);
DISPLAY 0.872340 (-2525 3650);
PAINT GREEN (-2525 3650);
DISPLAY INVISIBLE (-2525 3650);
FORCEPROP 1 LAST COMMENT_BODY TRUE
J 0
(-2895 3680);
DISPLAY 0.872340 (-2895 3680);
PAINT GREEN (-2895 3680);
DISPLAY INVISIBLE (-2895 3680);
FORCEPROP 2 LAST PATH I50
J 0
(-2650 3825);
DISPLAY 0.680851 (-2650 3825);
DISPLAY INVISIBLE (-2650 3825);
FORCEADD OFFPAGE..2
(-2850 3825);
FORCEPROP 2 LAST $XR0 288 
J 0
(-2661 3825);
DISPLAY 0.638298 (-2661 3825);
PAINT MONO (-2661 3825);
FORCEPROP 2 LAST CDS_LIB standard
J 0
(-2850 3825);
DISPLAY INVISIBLE (-2850 3825);
FORCEPROP 1 LAST OFFPAGE TRUE
J 0
(-2525 3700);
DISPLAY 0.872340 (-2525 3700);
PAINT GREEN (-2525 3700);
DISPLAY INVISIBLE (-2525 3700);
FORCEPROP 1 LAST COMMENT_BODY TRUE
J 0
(-2895 3730);
DISPLAY 0.872340 (-2895 3730);
PAINT GREEN (-2895 3730);
DISPLAY INVISIBLE (-2895 3730);
FORCEPROP 2 LAST PATH I51
J 0
(-2650 3875);
DISPLAY 0.680851 (-2650 3875);
DISPLAY INVISIBLE (-2650 3875);
FORCEADD Q_RES..2
(-3150 3075);
FORCEPROP 1 LAST LOCATION R4518
J 0
(-3105 3200);
DISPLAY 0.808511 (-3105 3200);
FORCEPROP 0 LAST $SEC 1
J 0
(-3100 3250);
DISPLAY 0.680851 (-3100 3250);
PAINT MONO (-3100 3250);
DISPLAY INVISIBLE (-3100 3250);
FORCEPROP 0 LAST CDS_SEC 1
J 0
(-3100 3250);
DISPLAY 1.021277 (-3100 3250);
DISPLAY INVISIBLE (-3100 3250);
FORCEPROP 1 LASTPIN (-3150 3175) $PN 1
J 0
(-3145 3137);
DISPLAY 0.787234 (-3145 3137);
PAINT MONO (-3145 3137);
FORCEPROP 1 LASTPIN (-3150 2975) $PN 2
J 0
(-3145 2985);
DISPLAY 0.787234 (-3145 2985);
PAINT MONO (-3145 2985);
FORCEPROP 1 LAST PACK_TYPE 0402LF
J 0
(-3100 2950);
DISPLAY 0.510638 (-3100 2950);
FORCEPROP 1 LAST TOLERANCE 1%
J 0
(-3105 3100);
DISPLAY 0.510638 (-3105 3100);
FORCEPROP 1 LAST VALUE 10K
J 0
(-3105 3150);
DISPLAY 0.510638 (-3105 3150);
FORCEPROP 1 LAST WATTAGE 1/16W
J 0
(-3110 3050);
DISPLAY 0.510638 (-3110 3050);
FORCEPROP 1 LAST MATERIAL CHIP
J 0
(-3110 3000);
DISPLAY 0.510638 (-3110 3000);
FORCEPROP 2 LAST CDS_LIB pure_quanta
J 0
(-3150 3075);
DISPLAY INVISIBLE (-3150 3075);
FORCEPROP 1 LAST PATH I52
J 0
(-3100 3250);
DISPLAY 0.978723 (-3100 3250);
PAINT WHITE (-3100 3250);
DISPLAY INVISIBLE (-3100 3250);
FORCEPROP 1 LAST PART_NUMBER CS31002FB08
J 0
(-3110 2950);
DISPLAY 0.510638 (-3110 2950);
DISPLAY INVISIBLE (-3110 2950);
FORCEADD Q_RES..2
(-2925 3075);
FORCEPROP 1 LAST LOCATION R4519
J 0
(-2880 3200);
DISPLAY 0.808511 (-2880 3200);
FORCEPROP 0 LAST $SEC 1
J 0
(-2875 3250);
DISPLAY 0.680851 (-2875 3250);
PAINT MONO (-2875 3250);
DISPLAY INVISIBLE (-2875 3250);
FORCEPROP 0 LAST CDS_SEC 1
J 0
(-2875 3250);
DISPLAY 1.021277 (-2875 3250);
DISPLAY INVISIBLE (-2875 3250);
FORCEPROP 1 LASTPIN (-2925 3175) $PN 1
J 0
(-2920 3137);
DISPLAY 0.787234 (-2920 3137);
PAINT MONO (-2920 3137);
FORCEPROP 1 LASTPIN (-2925 2975) $PN 2
J 0
(-2920 2985);
DISPLAY 0.787234 (-2920 2985);
PAINT MONO (-2920 2985);
FORCEPROP 1 LAST PACK_TYPE 0402LF
J 0
(-2875 2950);
DISPLAY 0.510638 (-2875 2950);
FORCEPROP 1 LAST TOLERANCE 1%
J 0
(-2880 3100);
DISPLAY 0.510638 (-2880 3100);
FORCEPROP 1 LAST VALUE 10K
J 0
(-2880 3150);
DISPLAY 0.510638 (-2880 3150);
FORCEPROP 1 LAST MATERIAL CHIP
J 0
(-2885 3000);
DISPLAY 0.510638 (-2885 3000);
FORCEPROP 1 LAST WATTAGE 1/16W
J 0
(-2885 3050);
DISPLAY 0.510638 (-2885 3050);
FORCEPROP 2 LAST CDS_LIB pure_quanta
J 0
(-2925 3075);
DISPLAY INVISIBLE (-2925 3075);
FORCEPROP 1 LAST PATH I53
J 0
(-2875 3250);
DISPLAY 0.978723 (-2875 3250);
PAINT WHITE (-2875 3250);
DISPLAY INVISIBLE (-2875 3250);
FORCEPROP 1 LAST PART_NUMBER CS31002FB08
J 0
(-2885 2950);
DISPLAY 0.510638 (-2885 2950);
DISPLAY INVISIBLE (-2885 2950);
FORCEADD Q_RES..2
(-2725 3100);
FORCEPROP 1 LAST LOCATION R4520
J 0
(-2680 3225);
DISPLAY 0.808511 (-2680 3225);
FORCEPROP 0 LAST $SEC 1
J 0
(-2675 3275);
DISPLAY 0.680851 (-2675 3275);
PAINT MONO (-2675 3275);
DISPLAY INVISIBLE (-2675 3275);
FORCEPROP 0 LAST CDS_SEC 1
J 0
(-2675 3275);
DISPLAY 1.021277 (-2675 3275);
DISPLAY INVISIBLE (-2675 3275);
FORCEPROP 1 LASTPIN (-2725 3200) $PN 1
J 0
(-2720 3162);
DISPLAY 0.787234 (-2720 3162);
PAINT MONO (-2720 3162);
FORCEPROP 1 LASTPIN (-2725 3000) $PN 2
J 0
(-2720 3010);
DISPLAY 0.787234 (-2720 3010);
PAINT MONO (-2720 3010);
FORCEPROP 1 LAST MATERIAL CHIP
J 0
(-2685 3025);
DISPLAY 0.510638 (-2685 3025);
FORCEPROP 1 LAST WATTAGE 1/16W
J 0
(-2685 3075);
DISPLAY 0.510638 (-2685 3075);
FORCEPROP 1 LAST PACK_TYPE 0402LF
J 0
(-2685 2925);
DISPLAY 0.510638 (-2685 2925);
FORCEPROP 1 LAST TOLERANCE 1%
J 0
(-2680 3125);
DISPLAY 0.510638 (-2680 3125);
FORCEPROP 1 LAST VALUE 10K
J 0
(-2680 3175);
DISPLAY 0.510638 (-2680 3175);
FORCEPROP 2 LAST CDS_LIB pure_quanta
J 0
(-2725 3100);
DISPLAY INVISIBLE (-2725 3100);
FORCEPROP 1 LAST PATH I55
J 0
(-2675 3275);
DISPLAY 0.978723 (-2675 3275);
PAINT WHITE (-2675 3275);
DISPLAY INVISIBLE (-2675 3275);
FORCEPROP 1 LAST PART_NUMBER CS31002FB08
J 0
(-2685 2975);
DISPLAY 0.510638 (-2685 2975);
DISPLAY INVISIBLE (-2685 2975);
FORCEADD OFFPAGE..2
(-2850 3875);
FORCEPROP 2 LAST $XR0 288 
J 0
(-2661 3875);
DISPLAY 0.638298 (-2661 3875);
PAINT MONO (-2661 3875);
FORCEPROP 2 LAST CDS_LIB standard
J 0
(-2850 3875);
DISPLAY INVISIBLE (-2850 3875);
FORCEPROP 1 LAST OFFPAGE TRUE
J 0
(-2525 3750);
DISPLAY 0.872340 (-2525 3750);
PAINT GREEN (-2525 3750);
DISPLAY INVISIBLE (-2525 3750);
FORCEPROP 1 LAST COMMENT_BODY TRUE
J 0
(-2895 3780);
DISPLAY 0.872340 (-2895 3780);
PAINT GREEN (-2895 3780);
DISPLAY INVISIBLE (-2895 3780);
FORCEPROP 2 LAST PATH I58
J 0
(-2650 3925);
DISPLAY 0.680851 (-2650 3925);
DISPLAY INVISIBLE (-2650 3925);
FORCEADD OFFPAGE..2
(-2850 3925);
FORCEPROP 2 LAST $XR0 277 
J 0
(-2661 3925);
DISPLAY 0.638298 (-2661 3925);
PAINT MONO (-2661 3925);
FORCEPROP 2 LAST CDS_LIB standard
J 0
(-2850 3925);
DISPLAY INVISIBLE (-2850 3925);
FORCEPROP 1 LAST OFFPAGE TRUE
J 0
(-2525 3800);
DISPLAY 0.872340 (-2525 3800);
PAINT GREEN (-2525 3800);
DISPLAY INVISIBLE (-2525 3800);
FORCEPROP 1 LAST COMMENT_BODY TRUE
J 0
(-2895 3830);
DISPLAY 0.872340 (-2895 3830);
PAINT GREEN (-2895 3830);
DISPLAY INVISIBLE (-2895 3830);
FORCEPROP 2 LAST PATH I59
J 0
(-2650 3975);
DISPLAY 0.680851 (-2650 3975);
DISPLAY INVISIBLE (-2650 3975);
FORCEADD Q_RES..1
(-7875 5225);
FORCEPROP 1 LAST LOCATION R4475
J 0
(-8100 5225);
DISPLAY 0.638298 (-8100 5225);
FORCEPROP 0 LAST SEC 1
J 0
(-7700 5375);
DISPLAY 0.680851 (-7700 5375);
PAINT MONO (-7700 5375);
DISPLAY INVISIBLE (-7700 5375);
FORCEPROP 1 LASTPIN (-7975 5225) $PN 1
J 0
(-7963 5237);
DISPLAY 0.787234 (-7963 5237);
PAINT MONO (-7963 5237);
FORCEPROP 1 LASTPIN (-7775 5225) $PN 2
J 0
(-7813 5237);
DISPLAY 0.787234 (-7813 5237);
PAINT MONO (-7813 5237);
FORCEPROP 1 LAST PACK_TYPE 0603LF
J 0
(-8025 5350);
DISPLAY 0.510638 (-8025 5350);
FORCEPROP 1 LAST WATTAGE 1/10W
J 2
(-7700 5350);
DISPLAY 0.510638 (-7700 5350);
FORCEPROP 1 LAST MATERIAL CHIP
J 0
(-7550 5225);
DISPLAY 0.638298 (-7550 5225);
FORCEPROP 1 LAST TOLERANCE 1%
J 0
(-7650 5225);
DISPLAY 0.638298 (-7650 5225);
FORCEPROP 1 LAST VALUE 1
J 2
(-7675 5225);
DISPLAY 0.638298 (-7675 5225);
FORCEPROP 2 LAST SEC_TYPE 0603LF
J 0
(-7925 5425);
DISPLAY 0.680851 (-7925 5425);
DISPLAY INVISIBLE (-7925 5425);
FORCEPROP 2 LAST CDS_LIB pure_quanta
J 0
(-7875 5225);
DISPLAY INVISIBLE (-7875 5225);
FORCEPROP 1 LAST PATH I6
J 0
(-7925 5375);
DISPLAY 0.978723 (-7925 5375);
PAINT WHITE (-7925 5375);
DISPLAY INVISIBLE (-7925 5375);
FORCEPROP 1 LAST PART_NUMBER CS-1003F900
J 0
(-8025 5300);
DISPLAY 0.510638 (-8025 5300);
DISPLAY INVISIBLE (-8025 5300);
FORCEADD OFFPAGE..2
(-2850 3975);
FORCEPROP 2 LAST $XR0 277 
J 0
(-2661 3975);
DISPLAY 0.638298 (-2661 3975);
PAINT MONO (-2661 3975);
FORCEPROP 2 LAST CDS_LIB standard
J 0
(-2850 3975);
DISPLAY INVISIBLE (-2850 3975);
FORCEPROP 1 LAST OFFPAGE TRUE
J 0
(-2525 3850);
DISPLAY 0.872340 (-2525 3850);
PAINT GREEN (-2525 3850);
DISPLAY INVISIBLE (-2525 3850);
FORCEPROP 1 LAST COMMENT_BODY TRUE
J 0
(-2895 3880);
DISPLAY 0.872340 (-2895 3880);
PAINT GREEN (-2895 3880);
DISPLAY INVISIBLE (-2895 3880);
FORCEPROP 2 LAST PATH I60
J 0
(-2650 4025);
DISPLAY 0.680851 (-2650 4025);
DISPLAY INVISIBLE (-2650 4025);
FORCEADD 9ZXL0451EKILFT..1
(-4850 3700);
FORCEPROP 1 LAST LOCATION U314
J 0
(-5316 4715);
DISPLAY 0.723404 (-5316 4715);
PAINT GREEN (-5316 4715);
FORCEPROP 0 LAST $SEC 1
J 0
(-5300 4850);
DISPLAY 0.680851 (-5300 4850);
PAINT MONO (-5300 4850);
DISPLAY INVISIBLE (-5300 4850);
FORCEPROP 0 LAST CDS_SEC 1
J 0
(-5300 4850);
DISPLAY 1.021277 (-5300 4850);
DISPLAY INVISIBLE (-5300 4850);
FORCEPROP 0 LASTPIN (-5475 3475) $PN 1
J 2
(-5485 3485);
DISPLAY 0.680851 (-5485 3485);
PAINT MONO (-5485 3485);
FORCEPROP 0 LASTPIN (-4225 4175) $PN 32
J 0
(-4215 4185);
DISPLAY 0.680851 (-4215 4185);
PAINT MONO (-4215 4185);
FORCEPROP 0 LASTPIN (-4225 3975) $PN 13
J 0
(-4215 3985);
DISPLAY 0.680851 (-4215 3985);
PAINT MONO (-4215 3985);
FORCEPROP 0 LASTPIN (-4225 3925) $PN 14
J 0
(-4215 3935);
DISPLAY 0.680851 (-4215 3935);
PAINT MONO (-4215 3935);
FORCEPROP 0 LASTPIN (-4225 3875) $PN 19
J 0
(-4215 3885);
DISPLAY 0.680851 (-4215 3885);
PAINT MONO (-4215 3885);
FORCEPROP 0 LASTPIN (-4225 3825) $PN 20
J 0
(-4215 3835);
DISPLAY 0.680851 (-4215 3835);
PAINT MONO (-4215 3835);
FORCEPROP 0 LASTPIN (-4225 3775) $PN 22
J 0
(-4215 3785);
DISPLAY 0.680851 (-4215 3785);
PAINT MONO (-4215 3785);
FORCEPROP 0 LASTPIN (-4225 3725) $PN 23
J 0
(-4215 3735);
DISPLAY 0.680851 (-4215 3735);
PAINT MONO (-4215 3735);
FORCEPROP 0 LASTPIN (-4225 3675) $PN 27
J 0
(-4215 3685);
DISPLAY 0.680851 (-4215 3685);
PAINT MONO (-4215 3685);
FORCEPROP 0 LASTPIN (-4225 3625) $PN 28
J 0
(-4215 3635);
DISPLAY 0.680851 (-4215 3635);
PAINT MONO (-4215 3635);
FORCEPROP 0 LASTPIN (-5475 3875) $PN 3
J 2
(-5485 3885);
DISPLAY 0.680851 (-5485 3885);
PAINT MONO (-5485 3885);
FORCEPROP 0 LASTPIN (-5475 3825) $PN 4
J 2
(-5485 3835);
DISPLAY 0.680851 (-5485 3835);
PAINT MONO (-5485 3835);
FORCEPROP 0 LASTPIN (-4225 3075) $PN 33
J 0
(-4215 3085);
DISPLAY 0.680851 (-4215 3085);
PAINT MONO (-4215 3085);
FORCEPROP 0 LASTPIN (-5475 3425) $PN 9
J 2
(-5485 3435);
DISPLAY 0.680851 (-5485 3435);
PAINT MONO (-5485 3435);
FORCEPROP 0 LASTPIN (-5475 3375) $PN 8
J 2
(-5485 3385);
DISPLAY 0.680851 (-5485 3385);
PAINT MONO (-5485 3385);
FORCEPROP 0 LASTPIN (-5475 3225) $PN 10
J 2
(-5485 3235);
DISPLAY 0.680851 (-5485 3235);
PAINT MONO (-5485 3235);
FORCEPROP 0 LASTPIN (-5475 3175) $PN 11
J 2
(-5485 3185);
DISPLAY 0.680851 (-5485 3185);
PAINT MONO (-5485 3185);
FORCEPROP 0 LASTPIN (-5475 3125) $PN 17
J 2
(-5485 3135);
DISPLAY 0.680851 (-5485 3135);
PAINT MONO (-5485 3135);
FORCEPROP 0 LASTPIN (-5475 3075) $PN 30
J 2
(-5485 3085);
DISPLAY 0.680851 (-5485 3085);
PAINT MONO (-5485 3085);
FORCEPROP 0 LASTPIN (-5475 3575) $PN 7
J 2
(-5485 3585);
DISPLAY 0.680851 (-5485 3585);
PAINT MONO (-5485 3585);
FORCEPROP 0 LASTPIN (-5475 3625) $PN 6
J 2
(-5485 3635);
DISPLAY 0.680851 (-5485 3635);
PAINT MONO (-5485 3635);
FORCEPROP 0 LASTPIN (-5475 4325) $PN 12
J 2
(-5485 4335);
DISPLAY 0.680851 (-5485 4335);
PAINT MONO (-5485 4335);
FORCEPROP 0 LASTPIN (-5475 4275) $PN 16
J 2
(-5485 4285);
DISPLAY 0.680851 (-5485 4285);
PAINT MONO (-5485 4285);
FORCEPROP 0 LASTPIN (-5475 4225) $PN 21
J 2
(-5485 4235);
DISPLAY 0.680851 (-5485 4235);
PAINT MONO (-5485 4235);
FORCEPROP 0 LASTPIN (-5475 4175) $PN 25
J 2
(-5485 4185);
DISPLAY 0.680851 (-5485 4185);
PAINT MONO (-5485 4185);
FORCEPROP 0 LASTPIN (-5475 4125) $PN 29
J 2
(-5485 4135);
DISPLAY 0.680851 (-5485 4135);
PAINT MONO (-5485 4135);
FORCEPROP 0 LASTPIN (-4225 4325) $PN 31
J 0
(-4215 4335);
DISPLAY 0.680851 (-4215 4335);
PAINT MONO (-4215 4335);
FORCEPROP 0 LASTPIN (-5475 4025) $PN 2
J 2
(-5485 4035);
DISPLAY 0.680851 (-5485 4035);
PAINT MONO (-5485 4035);
FORCEPROP 0 LASTPIN (-4225 3425) $PN 15
J 0
(-4215 3435);
DISPLAY 0.680851 (-4215 3435);
PAINT MONO (-4215 3435);
FORCEPROP 0 LASTPIN (-4225 3375) $PN 18
J 0
(-4215 3385);
DISPLAY 0.680851 (-4215 3385);
PAINT MONO (-4215 3385);
FORCEPROP 0 LASTPIN (-4225 3325) $PN 24
J 0
(-4215 3335);
DISPLAY 0.680851 (-4215 3335);
PAINT MONO (-4215 3335);
FORCEPROP 0 LASTPIN (-4225 3275) $PN 26
J 0
(-4215 3285);
DISPLAY 0.680851 (-4215 3285);
PAINT MONO (-4215 3285);
FORCEPROP 0 LASTPIN (-5475 3725) $PN 5
J 2
(-5485 3735);
DISPLAY 0.680851 (-5485 3735);
PAINT MONO (-5485 3735);
FORCEPROP 2 LAST VALUE 9ZXL0451EKILFT
J 0
(-5300 4750);
DISPLAY 1.021277 (-5300 4750);
FORCEPROP 2 LAST PART_TYPE SMLF
J 0
(-5300 4800);
DISPLAY 1.021277 (-5300 4800);
FORCEPROP 1 LAST MATERIAL IC
J 0
(-5316 4441);
DISPLAY 0.723404 (-5316 4441);
PAINT GREEN (-5316 4441);
FORCEPROP 1 LAST CDS_LMAN_SYM_OUTLINE -475,725,475,-725
J 0
(-4850 3700);
DISPLAY 0.468085 (-4850 3700);
PAINT GREEN (-4850 3700);
DISPLAY INVISIBLE (-4850 3700);
FORCEPROP 1 LAST NEEDS_NO_SIZE TRUE
J 0
(-4850 3700);
DISPLAY 0.723404 (-4850 3700);
PAINT GREEN (-4850 3700);
DISPLAY INVISIBLE (-4850 3700);
FORCEPROP 2 LAST CDS_LIB pure_quanta
J 0
(-4850 3700);
DISPLAY INVISIBLE (-4850 3700);
FORCEPROP 1 LAST PATH I63
J 0
(-4850 3700);
DISPLAY 0.723404 (-4850 3700);
PAINT GREEN (-4850 3700);
DISPLAY INVISIBLE (-4850 3700);
FORCEPROP 1 LAST PART_NUMBER AL000451003
J 0
(-5316 4568);
DISPLAY 0.723404 (-5316 4568);
PAINT GREEN (-5316 4568);
DISPLAY INVISIBLE (-5316 4568);
FORCEADD OFFPAGE..2
(-2850 3675);
FORCEPROP 2 LAST $XR0 310 
J 0
(-2661 3675);
DISPLAY 0.638298 (-2661 3675);
PAINT MONO (-2661 3675);
FORCEPROP 2 LAST CDS_LIB standard
J 0
(-2850 3675);
DISPLAY INVISIBLE (-2850 3675);
FORCEPROP 1 LAST OFFPAGE TRUE
J 0
(-2525 3550);
DISPLAY 0.872340 (-2525 3550);
PAINT GREEN (-2525 3550);
DISPLAY INVISIBLE (-2525 3550);
FORCEPROP 1 LAST COMMENT_BODY TRUE
J 0
(-2895 3580);
DISPLAY 0.872340 (-2895 3580);
PAINT GREEN (-2895 3580);
DISPLAY INVISIBLE (-2895 3580);
FORCEPROP 2 LAST PATH I64
J 0
(-2675 3750);
DISPLAY 0.680851 (-2675 3750);
DISPLAY INVISIBLE (-2675 3750);
FORCEADD OFFPAGE..2
(-2850 3625);
FORCEPROP 2 LAST $XR0 310 
J 0
(-2661 3625);
DISPLAY 0.638298 (-2661 3625);
PAINT MONO (-2661 3625);
FORCEPROP 2 LAST CDS_LIB standard
J 0
(-2850 3625);
DISPLAY INVISIBLE (-2850 3625);
FORCEPROP 1 LAST OFFPAGE TRUE
J 0
(-2525 3500);
DISPLAY 0.872340 (-2525 3500);
PAINT GREEN (-2525 3500);
DISPLAY INVISIBLE (-2525 3500);
FORCEPROP 1 LAST COMMENT_BODY TRUE
J 0
(-2895 3530);
DISPLAY 0.872340 (-2895 3530);
PAINT GREEN (-2895 3530);
DISPLAY INVISIBLE (-2895 3530);
FORCEPROP 2 LAST PATH I65
J 0
(-2675 3700);
DISPLAY 0.680851 (-2675 3700);
DISPLAY INVISIBLE (-2675 3700);
FORCEADD Q_RES..2
(-3375 3075);
FORCEPROP 1 LAST LOCATION R6802
J 0
(-3330 3200);
DISPLAY 0.808511 (-3330 3200);
FORCEPROP 0 LAST $SEC 1
J 0
(-3325 3250);
DISPLAY 0.680851 (-3325 3250);
PAINT MONO (-3325 3250);
DISPLAY INVISIBLE (-3325 3250);
FORCEPROP 0 LAST CDS_SEC 1
J 0
(-3325 3250);
DISPLAY 0.680851 (-3325 3250);
DISPLAY INVISIBLE (-3325 3250);
FORCEPROP 1 LASTPIN (-3375 3175) $PN 1
J 0
(-3370 3137);
DISPLAY 0.787234 (-3370 3137);
PAINT MONO (-3370 3137);
FORCEPROP 1 LASTPIN (-3375 2975) $PN 2
J 0
(-3370 2985);
DISPLAY 0.787234 (-3370 2985);
PAINT MONO (-3370 2985);
FORCEPROP 1 LAST MATERIAL CHIP
J 0
(-3335 3000);
DISPLAY 0.510638 (-3335 3000);
FORCEPROP 1 LAST PACK_TYPE 0402LF
J 0
(-3325 2950);
DISPLAY 0.510638 (-3325 2950);
FORCEPROP 1 LAST TOLERANCE 1%
J 0
(-3330 3100);
DISPLAY 0.510638 (-3330 3100);
FORCEPROP 1 LAST VALUE 10K
J 0
(-3330 3150);
DISPLAY 0.510638 (-3330 3150);
FORCEPROP 1 LAST WATTAGE 1/16W
J 0
(-3335 3050);
DISPLAY 0.510638 (-3335 3050);
FORCEPROP 2 LAST CDS_LIB pure_quanta
J 0
(-3375 3075);
DISPLAY INVISIBLE (-3375 3075);
FORCEPROP 1 LAST PATH I68
J 0
(-3325 3250);
DISPLAY 0.978723 (-3325 3250);
PAINT WHITE (-3325 3250);
DISPLAY INVISIBLE (-3325 3250);
FORCEPROP 1 LAST PART_NUMBER CS31002FB08
J 0
(-3335 2950);
DISPLAY 0.510638 (-3335 2950);
DISPLAY INVISIBLE (-3335 2950);
FORCEADD Q_CAP..1
(-7500 5875);
FORCEPROP 1 LAST LOCATION C76
J 0
(-7450 5975);
DISPLAY 0.808511 (-7450 5975);
FORCEPROP 0 LAST $SEC 1
J 0
(-7450 6025);
DISPLAY 0.680851 (-7450 6025);
PAINT MONO (-7450 6025);
DISPLAY INVISIBLE (-7450 6025);
FORCEPROP 0 LAST CDS_SEC 1
J 0
(-7450 6025);
DISPLAY 0.680851 (-7450 6025);
DISPLAY INVISIBLE (-7450 6025);
FORCEPROP 1 LASTPIN (-7500 5975) $PN 1
J 0
(-7490 5955);
DISPLAY 0.787234 (-7490 5955);
PAINT MONO (-7490 5955);
FORCEPROP 1 LASTPIN (-7500 5775) $PN 2
J 0
(-7490 5755);
DISPLAY 0.787234 (-7490 5755);
PAINT MONO (-7490 5755);
FORCEPROP 1 LAST VOLTAGE 6.3V
J 0
(-7450 5875);
DISPLAY 0.510638 (-7450 5875);
FORCEPROP 1 LAST VALUE 10UF
J 0
(-7450 5925);
DISPLAY 0.510638 (-7450 5925);
FORCEPROP 1 LAST MATERIAL X6S
J 0
(-7450 5775);
DISPLAY 0.510638 (-7450 5775);
FORCEPROP 1 LAST PACK_TYPE C0402
J 0
(-7450 5725);
DISPLAY 0.510638 (-7450 5725);
FORCEPROP 1 LAST TOLERANCE 20%
J 0
(-7450 5825);
DISPLAY 0.510638 (-7450 5825);
FORCEPROP 2 LAST CDS_LIB pure_quanta
J 0
(-7500 5875);
DISPLAY INVISIBLE (-7500 5875);
FORCEPROP 1 LAST PATH I69
J 0
(-7450 6025);
DISPLAY 0.978723 (-7450 6025);
PAINT WHITE (-7450 6025);
DISPLAY INVISIBLE (-7450 6025);
FORCEPROP 1 LAST PART_NUMBER CH6101MEB01
J 0
(-7450 5675);
DISPLAY 0.510638 (-7450 5675);
DISPLAY INVISIBLE (-7450 5675);
FORCEADD Q_CAP..1
(-7475 5075);
FORCEPROP 1 LAST LOCATION C77
J 0
(-7425 5175);
DISPLAY 0.808511 (-7425 5175);
FORCEPROP 0 LAST $SEC 1
J 0
(-7425 5225);
DISPLAY 0.680851 (-7425 5225);
PAINT MONO (-7425 5225);
DISPLAY INVISIBLE (-7425 5225);
FORCEPROP 0 LAST CDS_SEC 1
J 0
(-7425 5225);
DISPLAY 0.680851 (-7425 5225);
DISPLAY INVISIBLE (-7425 5225);
FORCEPROP 1 LASTPIN (-7475 5175) $PN 1
J 0
(-7465 5155);
DISPLAY 0.787234 (-7465 5155);
PAINT MONO (-7465 5155);
FORCEPROP 1 LASTPIN (-7475 4975) $PN 2
J 0
(-7465 4955);
DISPLAY 0.787234 (-7465 4955);
PAINT MONO (-7465 4955);
FORCEPROP 1 LAST VALUE 10UF
J 0
(-7425 5125);
DISPLAY 0.510638 (-7425 5125);
FORCEPROP 1 LAST MATERIAL X6S
J 0
(-7425 4975);
DISPLAY 0.510638 (-7425 4975);
FORCEPROP 1 LAST TOLERANCE 20%
J 0
(-7425 5025);
DISPLAY 0.510638 (-7425 5025);
FORCEPROP 1 LAST VOLTAGE 6.3V
J 0
(-7425 5075);
DISPLAY 0.510638 (-7425 5075);
FORCEPROP 1 LAST PACK_TYPE C0402
J 0
(-7425 4925);
DISPLAY 0.510638 (-7425 4925);
FORCEPROP 2 LAST CDS_LIB pure_quanta
J 0
(-7475 5075);
DISPLAY INVISIBLE (-7475 5075);
FORCEPROP 1 LAST PATH I70
J 0
(-7425 5225);
DISPLAY 0.978723 (-7425 5225);
PAINT WHITE (-7425 5225);
DISPLAY INVISIBLE (-7425 5225);
FORCEPROP 1 LAST PART_NUMBER CH6101MEB01
J 0
(-7425 4875);
DISPLAY 0.510638 (-7425 4875);
DISPLAY INVISIBLE (-7425 4875);
FORCEADD Q_CAP..1
(-4925 5525);
FORCEPROP 1 LAST LOCATION C2328
J 0
(-4875 5625);
DISPLAY 0.808511 (-4875 5625);
FORCEPROP 0 LAST $SEC 1
J 0
(-4875 5675);
DISPLAY 0.680851 (-4875 5675);
PAINT MONO (-4875 5675);
DISPLAY INVISIBLE (-4875 5675);
FORCEPROP 0 LAST CDS_SEC 1
J 0
(-4875 5675);
DISPLAY 0.680851 (-4875 5675);
DISPLAY INVISIBLE (-4875 5675);
FORCEPROP 1 LASTPIN (-4925 5625) $PN 1
J 0
(-4915 5605);
DISPLAY 0.787234 (-4915 5605);
PAINT MONO (-4915 5605);
FORCEPROP 1 LASTPIN (-4925 5425) $PN 2
J 0
(-4915 5405);
DISPLAY 0.787234 (-4915 5405);
PAINT MONO (-4915 5405);
FORCEPROP 1 LAST TOLERANCE 20%
J 0
(-4875 5475);
DISPLAY 0.510638 (-4875 5475);
FORCEPROP 1 LAST MATERIAL X6S
J 0
(-4875 5425);
DISPLAY 0.510638 (-4875 5425);
FORCEPROP 1 LAST PACK_TYPE C0402
J 0
(-4875 5375);
DISPLAY 0.510638 (-4875 5375);
FORCEPROP 1 LAST VALUE 10UF
J 0
(-4875 5575);
DISPLAY 0.510638 (-4875 5575);
FORCEPROP 1 LAST VOLTAGE 6.3V
J 0
(-4875 5525);
DISPLAY 0.510638 (-4875 5525);
FORCEPROP 2 LAST CDS_LIB pure_quanta
J 0
(-4925 5525);
DISPLAY INVISIBLE (-4925 5525);
FORCEPROP 1 LAST PATH I71
J 0
(-4875 5675);
DISPLAY 0.978723 (-4875 5675);
PAINT WHITE (-4875 5675);
DISPLAY INVISIBLE (-4875 5675);
FORCEPROP 1 LAST PART_NUMBER CH6101MEB01
J 0
(-4875 5325);
DISPLAY 0.510638 (-4875 5325);
DISPLAY INVISIBLE (-4875 5325);
FORCEADD UNIVERSAL_GND..1
(-2725 2750);
FORCEPROP 3 LASTPIN (-2725 2800) SIG_NAME GND\g
J 0
(-2715 2810);
DISPLAY 0.659574 (-2715 2810);
PAINT MONO (-2715 2810);
DISPLAY INVISIBLE (-2715 2810);
FORCEPROP 2 LAST CDS_LIB pure_quanta_power
J 0
(-2725 2750);
DISPLAY INVISIBLE (-2725 2750);
FORCEPROP 1 LAST HDL_POWER GND
J 1
(-2700 2675);
DISPLAY 0.872340 (-2700 2675);
PAINT GREEN (-2700 2675);
DISPLAY INVISIBLE (-2700 2675);
FORCEPROP 1 LAST PATH I72
J 0
(-2650 2750);
DISPLAY 0.872340 (-2650 2750);
PAINT AQUA (-2650 2750);
DISPLAY INVISIBLE (-2650 2750);
FORCEADD Q_RES..2
R 2
(-7200 3700);
FORCEPROP 1 LAST LOCATION R4476
J 2
(-7245 3825);
DISPLAY 0.808511 (-7245 3825);
FORCEPROP 0 LAST $SEC 1
J 0
(-7225 3875);
DISPLAY 0.680851 (-7225 3875);
PAINT MONO (-7225 3875);
DISPLAY INVISIBLE (-7225 3875);
FORCEPROP 0 LAST CDS_SEC 1
J 0
(-7225 3875);
DISPLAY 0.680851 (-7225 3875);
DISPLAY INVISIBLE (-7225 3875);
FORCEPROP 1 LASTPIN (-7200 3800) $PN 1
J 2
(-7205 3762);
DISPLAY 0.787234 (-7205 3762);
PAINT MONO (-7205 3762);
FORCEPROP 1 LASTPIN (-7200 3600) $PN 2
J 2
(-7205 3610);
DISPLAY 0.787234 (-7205 3610);
PAINT MONO (-7205 3610);
FORCEPROP 1 LAST PACK_TYPE 0402LF
J 2
(-7250 3575);
DISPLAY 0.638298 (-7250 3575);
FORCEPROP 1 LAST MATERIAL CHIP
J 2
(-7240 3625);
DISPLAY 0.638298 (-7240 3625);
FORCEPROP 1 LAST VALUE 10K
J 2
(-7245 3775);
DISPLAY 0.638298 (-7245 3775);
FORCEPROP 1 LAST WATTAGE 1/16W
J 2
(-7240 3675);
DISPLAY 0.638298 (-7240 3675);
FORCEPROP 1 LAST TOLERANCE 1%
J 2
(-7245 3725);
DISPLAY 0.510638 (-7245 3725);
FORCEPROP 2 LAST CDS_LIB pure_quanta
J 2
(-7200 3700);
DISPLAY INVISIBLE (-7200 3700);
FORCEPROP 1 LAST PATH I73
J 2
(-7250 3875);
DISPLAY 0.978723 (-7250 3875);
PAINT WHITE (-7250 3875);
DISPLAY INVISIBLE (-7250 3875);
FORCEPROP 1 LAST PART_NUMBER CS31002FB08
J 2
(-7240 3575);
DISPLAY 0.510638 (-7240 3575);
DISPLAY INVISIBLE (-7240 3575);
FORCEADD UNIVERSAL_POWER..1
(-7200 4050);
FORCEPROP 3 LASTPIN (-7200 4000) SIG_NAME P3V3_AUX\g
J 0
(-7190 4010);
DISPLAY 0.659574 (-7190 4010);
PAINT MONO (-7190 4010);
DISPLAY INVISIBLE (-7190 4010);
FORCEPROP 1 LAST HDL_POWER P3V3_AUX
J 1
(-7200 4100);
DISPLAY 0.872340 (-7200 4100);
PAINT YELLOW (-7200 4100);
FORCEPROP 2 LAST CDS_LIB pure_quanta_power
J 0
(-7200 4050);
DISPLAY INVISIBLE (-7200 4050);
FORCEPROP 1 LAST PATH I74
J 0
(-7150 4075);
DISPLAY 0.872340 (-7150 4075);
PAINT AQUA (-7150 4075);
DISPLAY INVISIBLE (-7150 4075);
FORCEADD QUANTA_TITLE_BLOCK_C..1
(-225 200);
FORCEPROP 0 LAST CDS_CON_LAST_MODIFIED Thu Sep 14 16:12:56 2023
J 0
(-2110 215);
PAINT MONO (-2110 215);
DISPLAY INVISIBLE (-2110 215);
FORCEPROP 1 LAST CUSTOM_TXT_CDS <CON_LAST_MODIFIED>
J 0
(-2110 215);
DISPLAY 0.978723 (-2110 215);
FORCEPROP 2 LAST CUSTOM_TXT_CDS <XR_PAGE_TITLE>
J 0
(-8115 5450);
DISPLAY 0.638298 (-8115 5450);
PAINT PINK (-8115 5450);
DISPLAY INVISIBLE (-8115 5450);
FORCEPROP 1 LAST CUSTOM_TXT_CDS <NAME_2>
J 0
(-3400 250);
FORCEPROP 1 LAST CUSTOM_TXT_CDS <NAME_1>
J 0
(-3400 375);
FORCEPROP 1 LAST CUSTOM_TXT_CDS <Q_NUMBER>
J 0
(-1628 303);
DISPLAY 1.212766 (-1628 303);
FORCEPROP 1 LAST CUSTOM_TXT_CDS <Q_PROJ>
J 0
(-2607 302);
DISPLAY 1.212766 (-2607 302);
FORCEPROP 1 LAST CUSTOM_TXT_CDS <Q_REV>
J 0
(-409 303);
DISPLAY 1.212766 (-409 303);
FORCEPROP 1 LAST CUSTOM_TXT_CDS <CON_PAGE_NUM> OF <CON_TOTAL_PAGES>
J 0
(-671 218);
DISPLAY 0.978723 (-671 218);
FORCEPROP 1 LAST Q_TITLE CLK BUFFER _ 9ZXL045 _ CPU0 RETIMER
J 0
(-9591 226);
DISPLAY 2.446809 (-9591 226);
PAINT GREEN (-9591 226);
FORCEPROP 2 LAST CDS_LIB pure_quanta
J 0
(-225 200);
PAINT MONO (-225 200);
DISPLAY INVISIBLE (-225 200);
FORCEPROP 1 LAST CDS_LMAN_SYM_OUTLINE -9475,6775,100,-125
J 0
(-225 200);
DISPLAY 0.468085 (-225 200);
PAINT GREEN (-225 200);
DISPLAY INVISIBLE (-225 200);
FORCEPROP 2 LAST PAGE_BORDER TRUE
J 0
(-8115 5450);
DISPLAY 0.638298 (-8115 5450);
PAINT PINK (-8115 5450);
DISPLAY INVISIBLE (-8115 5450);
FORCEPROP 2 LAST CDS_XR_PAGE_TITLE CR-182 : @T6G_MB_LIB.T6G(SCH_1):PAGE182
J 0
(-8115 5450);
DISPLAY 0.638298 (-8115 5450);
PAINT PINK (-8115 5450);
DISPLAY INVISIBLE (-8115 5450);
FORCEPROP 1 LAST Q_DEPT BU9
J 1
(-3988 249);
DISPLAY 1.957447 (-3988 249);
PAINT GREEN (-3988 249);
DISPLAY INVISIBLE (-3988 249);
FORCEPROP 1 LAST COMMENT_BODY TRUE
J 0
(-213 187);
DISPLAY 0.978723 (-213 187);
PAINT GREEN (-213 187);
DISPLAY INVISIBLE (-213 187);
FORCEADD DNS..2
(-6250 1350);
PAINT RED (-6250 1350);
FORCEPROP 2 LAST CDS_LIB mstr_misc
J 0
(-6250 1350);
DISPLAY INVISIBLE (-6250 1350);
FORCEPROP 1 LAST COMMENT_BODY TRUE
R 1
J 0
(-6175 1125);
DISPLAY 0.872340 (-6175 1125);
PAINT GREEN (-6175 1125);
DISPLAY INVISIBLE (-6175 1125);
WIRE 16 -1 (-6250 1175)(-6250 1275);
WIRE 16 -1 (-6250 2100)(-6250 1900);
WIRE 16 -1 (-5475 4025)(-6175 4025);
WIRE 16 -1 (-6175 4025)(-6175 4250);
WIRE 16 -1 (-4250 1125)(-4250 1225);
WIRE 16 -1 (-4250 2050)(-4250 1900);
WIRE 16 -1 (-4225 4325)(-3900 4325);
WIRE 16 -1 (-3900 4325)(-3900 4550);
WIRE 16 -1 (-7200 3800)(-7200 4000);
WIRE 16 -1 (-5475 3375)(-6900 3375);
FORCEPROP 2 LAST SIG_NAME NC_U314_FBOUT_N
J 0
(-6385 3385);
DISPLAY 0.680851 (-6385 3385);
PAINT SKYBLUE (-6385 3385);
FORCEPROP 2 LASTPROP $XRERR UNIQUE?
J 0
(-7140 3375);
DISPLAY 0.638298 (-7140 3375);
PAINT MONO (-7140 3375);
DISPLAY INVISIBLE (-7140 3375);
WIRE 16 -1 (-5475 3225)(-6900 3225);
FORCEPROP 2 LAST SIG_NAME NC_U314_NC0
J 0
(-6385 3235);
DISPLAY 0.680851 (-6385 3235);
PAINT SKYBLUE (-6385 3235);
FORCEPROP 2 LASTPROP $XRERR UNIQUE?
J 0
(-7140 3225);
DISPLAY 0.638298 (-7140 3225);
PAINT MONO (-7140 3225);
DISPLAY INVISIBLE (-7140 3225);
WIRE 16 -1 (-5475 3075)(-6900 3075);
FORCEPROP 2 LAST SIG_NAME NC_U314_NC3
J 0
(-6385 3085);
DISPLAY 0.680851 (-6385 3085);
PAINT SKYBLUE (-6385 3085);
FORCEPROP 2 LASTPROP $XRERR UNIQUE?
J 0
(-7140 3075);
DISPLAY 0.638298 (-7140 3075);
PAINT MONO (-7140 3075);
DISPLAY INVISIBLE (-7140 3075);
WIRE 16 -1 (-3375 2975)(-3375 2875);
WIRE 16 -1 (-3375 2875)(-3150 2875);
WIRE 16 -1 (-3150 2875)(-2925 2875);
WIRE 16 -1 (-3150 2975)(-3150 2875);
WIRE 16 -1 (-2925 2875)(-2725 2875);
WIRE 16 -1 (-2925 2975)(-2925 2875);
WIRE 16 -1 (-2725 3000)(-2725 2875);
WIRE 16 -1 (-2725 2875)(-2725 2800);
WIRE 16 -1 (-4225 3075)(-4025 3075);
WIRE 16 -1 (-4025 2825)(-4025 3075);
WIRE 16 -1 (-6250 1475)(-6250 1575);
WIRE 16 -1 (-5575 1575)(-6250 1575);
FORCEPROP 2 LAST SIG_NAME CLK_9ZXL045_P0_SADR0
J 0
(-6185 1585);
DISPLAY 0.553191 (-6185 1585);
PAINT SKYBLUE (-6185 1585);
WIRE 16 -1 (-6250 1700)(-6250 1575);
WIRE 16 -1 (-5350 5725)(-4925 5725);
WIRE 16 -1 (-4575 5725)(-4925 5725);
WIRE 16 -1 (-4925 5625)(-4925 5725);
WIRE 16 -1 (-4575 5725)(-4325 5725);
WIRE 16 -1 (-4575 5625)(-4575 5725);
WIRE 16 -1 (-4325 5725)(-4075 5725);
WIRE 16 -1 (-4325 5625)(-4325 5725);
WIRE 16 -1 (-3825 5725)(-4075 5725);
WIRE 16 -1 (-4075 5625)(-4075 5725);
WIRE 16 -1 (-3550 5725)(-3825 5725);
WIRE 16 -1 (-3825 5725)(-3825 5625);
WIRE 16 -1 (-3550 5825)(-3550 5725);
WIRE 16 -1 (-3550 5725)(-3550 5625);
WIRE 16 -1 (-4925 5425)(-4925 5300);
WIRE 16 -1 (-4925 5300)(-4575 5300);
WIRE 16 -1 (-4575 5300)(-4325 5300);
WIRE 16 -1 (-4575 5425)(-4575 5300);
WIRE 16 -1 (-4075 5300)(-4325 5300);
WIRE 16 -1 (-4325 5425)(-4325 5300);
WIRE 16 -1 (-4075 5300)(-3825 5300);
WIRE 16 -1 (-4075 5425)(-4075 5300);
WIRE 16 -1 (-3550 5300)(-3825 5300);
WIRE 16 -1 (-3825 5300)(-3825 5425);
WIRE 16 -1 (-3550 5425)(-3550 5300);
WIRE 16 -1 (-3550 5225)(-3550 5300);
WIRE 16 -1 (-7825 6050)(-7500 6050);
WIRE 16 -1 (-7500 6050)(-7150 6050);
WIRE 16 -1 (-7500 6050)(-7500 5975);
WIRE 16 -1 (-7150 6075)(-7150 6050);
WIRE 16 -1 (-7150 6050)(-7150 5975);
WIRE 16 -1 (-8875 6050)(-9200 6050);
WIRE 16 -1 (-9200 6100)(-9200 6050);
WIRE 16 -1 (-5900 5725)(-5550 5725);
WIRE 16 -1 (-5900 5800)(-5900 5725);
WIRE 16 -1 (-5475 4125)(-5775 4125);
WIRE 16 -1 (-5775 4125)(-5775 4175);
WIRE 16 -1 (-5475 4175)(-5775 4175);
WIRE 16 -1 (-5775 4175)(-5775 4225);
WIRE 16 -1 (-5475 4225)(-5775 4225);
WIRE 16 -1 (-5775 4225)(-5775 4275);
WIRE 16 -1 (-5475 4275)(-5775 4275);
WIRE 16 -1 (-5775 4275)(-5775 4325);
WIRE 16 -1 (-5475 4325)(-5775 4325);
WIRE 16 -1 (-5775 4325)(-5775 4550);
WIRE 16 -1 (-7150 5650)(-7150 5775);
WIRE 16 -1 (-7150 5550)(-7150 5650);
WIRE 16 -1 (-7500 5650)(-7150 5650);
WIRE 16 -1 (-7500 5775)(-7500 5650);
WIRE 16 -1 (-7775 5225)(-7475 5225);
WIRE 16 -1 (-7475 5225)(-7125 5225);
WIRE 16 -1 (-7475 5175)(-7475 5225);
WIRE 16 -1 (-7125 5275)(-7125 5225);
WIRE 16 -1 (-7125 5225)(-7125 5175);
WIRE 16 -1 (-7125 4850)(-7125 4975);
WIRE 16 -1 (-7125 4750)(-7125 4850);
WIRE 16 -1 (-7475 4850)(-7125 4850);
WIRE 16 -1 (-7475 4975)(-7475 4850);
WIRE 16 -1 (-5475 3725)(-6475 3725);
FORCEPROP 2 LAST SIG_NAME CLK_9ZXL045_P0_SADR0
J 0
(-6410 3735);
DISPLAY 0.702128 (-6410 3735);
PAINT SKYBLUE (-6410 3735);
WIRE 16 -1 (-3575 1575)(-4250 1575);
FORCEPROP 2 LAST SIG_NAME CLK_9ZXL045_P0_HIBW
J 0
(-4185 1585);
DISPLAY 0.553191 (-4185 1585);
PAINT SKYBLUE (-4185 1585);
WIRE 16 -1 (-4250 1700)(-4250 1575);
WIRE 16 -1 (-4250 1575)(-4250 1425);
WIRE 16 -1 (-3550 4175)(-4225 4175);
FORCEPROP 2 LAST SIG_NAME CLK_9ZXL045_P0_HIBW
J 0
(-4060 4185);
DISPLAY 0.553191 (-4060 4185);
PAINT SKYBLUE (-4060 4185);
WIRE 16 -1 (-5475 3825)(-6475 3825);
FORCEPROP 2 LAST SIG_NAME CLK_100M_CPU0_CLK13_DN
J 0
(-6410 3835);
DISPLAY 0.680851 (-6410 3835);
PAINT SKYBLUE (-6410 3835);
WIRE 16 -1 (-5475 3625)(-6650 3625);
FORCEPROP 2 LAST SIG_NAME SMB_9ZXL045_P0_SDA
J 0
(-6560 3635);
DISPLAY 0.702128 (-6560 3635);
PAINT SKYBLUE (-6560 3635);
WIRE 16 -1 (-8175 5225)(-8175 6050);
WIRE 16 -1 (-8175 5225)(-7975 5225);
WIRE 16 -1 (-8025 6050)(-8175 6050);
WIRE 16 -1 (-8675 6050)(-8175 6050);
FORCEPROP 2 LAST SIG_NAME P3V3_9ZXL045_P0
J 0
(-8610 6060);
DISPLAY 0.638298 (-8610 6060);
PAINT SKYBLUE (-8610 6060);
FORCEPROP 2 LASTPROP $XRERR UNIQUE?
J 0
(-8850 6060);
DISPLAY 0.638298 (-8850 6060);
PAINT MONO (-8850 6060);
DISPLAY INVISIBLE (-8850 6060);
WIRE 16 -1 (-5475 3575)(-6650 3575);
FORCEPROP 2 LAST SIG_NAME SMB_9ZXL045_P0_SCL
J 0
(-6560 3585);
DISPLAY 0.702128 (-6560 3585);
PAINT SKYBLUE (-6560 3585);
WIRE 16 -1 (-7200 3600)(-7200 3475);
WIRE 16 -1 (-5475 3475)(-7200 3475);
FORCEPROP 2 LAST SIG_NAME FM_9ZXL045_P0_DEV_EN
J 0
(-6435 3485);
DISPLAY 0.680851 (-6435 3485);
PAINT SKYBLUE (-6435 3485);
FORCEPROP 2 LASTPROP $XRERR UNIQUE?
J 0
(-6675 3485);
DISPLAY 0.638298 (-6675 3485);
PAINT MONO (-6675 3485);
DISPLAY INVISIBLE (-6675 3485);
WIRE 16 -1 (-5475 3425)(-6900 3425);
FORCEPROP 2 LAST SIG_NAME NC_U314_FBOUT
J 0
(-6385 3435);
DISPLAY 0.680851 (-6385 3435);
PAINT SKYBLUE (-6385 3435);
FORCEPROP 2 LASTPROP $XRERR UNIQUE?
J 0
(-7140 3425);
DISPLAY 0.638298 (-7140 3425);
PAINT MONO (-7140 3425);
DISPLAY INVISIBLE (-7140 3425);
WIRE 16 -1 (-5475 3175)(-6900 3175);
FORCEPROP 2 LAST SIG_NAME NC_U314_NC1
J 0
(-6385 3185);
DISPLAY 0.680851 (-6385 3185);
PAINT SKYBLUE (-6385 3185);
FORCEPROP 2 LASTPROP $XRERR UNIQUE?
J 0
(-7140 3175);
DISPLAY 0.638298 (-7140 3175);
PAINT MONO (-7140 3175);
DISPLAY INVISIBLE (-7140 3175);
WIRE 16 -1 (-5475 3125)(-6900 3125);
FORCEPROP 2 LAST SIG_NAME NC_U314_NC2
J 0
(-6385 3135);
DISPLAY 0.680851 (-6385 3135);
PAINT SKYBLUE (-6385 3135);
FORCEPROP 2 LASTPROP $XRERR UNIQUE?
J 0
(-7140 3125);
DISPLAY 0.638298 (-7140 3125);
PAINT MONO (-7140 3125);
DISPLAY INVISIBLE (-7140 3125);
WIRE 16 -1 (-3150 3325)(-3150 3175);
WIRE 16 -1 (-4225 3325)(-3150 3325);
FORCEPROP 2 LAST SIG_NAME FM_9ZXL045_P0_2_OE_N
J 0
(-4060 3335);
DISPLAY 0.680851 (-4060 3335);
PAINT SKYBLUE (-4060 3335);
FORCEPROP 2 LASTPROP $XRERR UNIQUE?
J 0
(-4300 3335);
DISPLAY 0.638298 (-4300 3335);
PAINT MONO (-4300 3335);
DISPLAY INVISIBLE (-4300 3335);
WIRE 16 -1 (-2925 3375)(-2925 3175);
WIRE 16 -1 (-4225 3375)(-2925 3375);
FORCEPROP 2 LAST SIG_NAME FM_9ZXL045_P0_1_OE_N
J 0
(-4060 3385);
DISPLAY 0.680851 (-4060 3385);
PAINT SKYBLUE (-4060 3385);
FORCEPROP 2 LASTPROP $XRERR UNIQUE?
J 0
(-4300 3385);
DISPLAY 0.638298 (-4300 3385);
PAINT MONO (-4300 3385);
DISPLAY INVISIBLE (-4300 3385);
WIRE 16 -1 (-2725 3425)(-2725 3200);
WIRE 16 -1 (-4225 3425)(-2725 3425);
FORCEPROP 2 LAST SIG_NAME FM_9ZXL045_P0_0_OE_N
J 0
(-4060 3435);
DISPLAY 0.680851 (-4060 3435);
PAINT SKYBLUE (-4060 3435);
FORCEPROP 2 LASTPROP $XRERR UNIQUE?
J 0
(-4300 3435);
DISPLAY 0.638298 (-4300 3435);
PAINT MONO (-4300 3435);
DISPLAY INVISIBLE (-4300 3435);
WIRE 16 -1 (-2900 3625)(-4225 3625);
FORCEPROP 2 LAST SIG_NAME CLK_100M_RETIMER_CPU0_P3_R_DN
J 0
(-4060 3635);
DISPLAY 0.702128 (-4060 3635);
PAINT SKYBLUE (-4060 3635);
WIRE 16 -1 (-2900 3725)(-4225 3725);
FORCEPROP 2 LAST SIG_NAME CLK_100M_RETIMER_CPU0_P2_R_DN
J 0
(-4060 3735);
DISPLAY 0.702128 (-4060 3735);
PAINT SKYBLUE (-4060 3735);
WIRE 16 -1 (-2900 3825)(-4225 3825);
FORCEPROP 2 LAST SIG_NAME CLK_100M_RETIMER_CPU0_P1_R_DN
J 0
(-4060 3835);
DISPLAY 0.702128 (-4060 3835);
PAINT SKYBLUE (-4060 3835);
WIRE 16 -1 (-2900 3875)(-4225 3875);
FORCEPROP 2 LAST SIG_NAME CLK_100M_RETIMER_CPU0_P1_R_DP
J 0
(-4060 3885);
DISPLAY 0.702128 (-4060 3885);
PAINT SKYBLUE (-4060 3885);
WIRE 16 -1 (-5475 3875)(-6475 3875);
FORCEPROP 2 LAST SIG_NAME CLK_100M_CPU0_CLK13_DP
J 0
(-6410 3885);
DISPLAY 0.680851 (-6410 3885);
PAINT SKYBLUE (-6410 3885);
WIRE 16 -1 (-2900 3675)(-4225 3675);
FORCEPROP 0 LAST SIG_NAME CLK_100M_RETIMER_CPU0_P3_R_DP
J 0
(-4060 3685);
DISPLAY 0.702128 (-4060 3685);
PAINT SKYBLUE (-4060 3685);
WIRE 16 -1 (-2900 3925)(-4225 3925);
FORCEPROP 2 LAST SIG_NAME CLK_100M_RETIMER_CPU0_P0_R_DN
J 0
(-4060 3935);
DISPLAY 0.702128 (-4060 3935);
PAINT SKYBLUE (-4060 3935);
WIRE 16 -1 (-2900 3775)(-4225 3775);
FORCEPROP 2 LAST SIG_NAME CLK_100M_RETIMER_CPU0_P2_R_DP
J 0
(-4060 3785);
DISPLAY 0.702128 (-4060 3785);
PAINT SKYBLUE (-4060 3785);
WIRE 16 -1 (-2900 3975)(-4225 3975);
FORCEPROP 2 LAST SIG_NAME CLK_100M_RETIMER_CPU0_P0_R_DP
J 0
(-4060 3985);
DISPLAY 0.702128 (-4060 3985);
PAINT SKYBLUE (-4060 3985);
WIRE 16 -1 (-3375 3275)(-3375 3175);
WIRE 16 -1 (-4225 3275)(-3375 3275);
FORCEPROP 2 LAST SIG_NAME FM_9ZXL045_P0_3_OE_N
J 0
(-4060 3285);
DISPLAY 0.680851 (-4060 3285);
PAINT SKYBLUE (-4060 3285);
FORCEPROP 2 LASTPROP $XRERR UNIQUE?
J 0
(-4300 3285);
DISPLAY 0.638298 (-4300 3285);
PAINT MONO (-4300 3285);
DISPLAY INVISIBLE (-4300 3285);
DOT 1 (-4925 5725);
DOT 1 (-7475 5225);
DOT 1 (-7500 6050);
DOT 1 (-4075 5725);
DOT 1 (-5775 4225);
DOT 1 (-4325 5725);
DOT 1 (-6250 1575);
DOT 1 (-4250 1575);
DOT 1 (-8175 6050);
DOT 1 (-7125 5225);
DOT 1 (-7150 6050);
DOT 1 (-4575 5300);
DOT 1 (-4325 5300);
DOT 1 (-4075 5300);
DOT 1 (-3825 5300);
DOT 1 (-3825 5725);
DOT 1 (-3550 5300);
DOT 1 (-3550 5725);
DOT 1 (-2725 2875);
DOT 1 (-5775 4275);
DOT 1 (-5775 4325);
DOT 1 (-7125 4850);
DOT 1 (-5775 4175);
DOT 1 (-4575 5725);
DOT 1 (-7150 5650);
DOT 1 (-3150 2875);
DOT 1 (-2925 2875);
FORCENOTE
9ZXL045 ADDRESS: 0XDE(8-BIT)/0X6F(7-BIT)
(-5675 2550) 0;
DISPLAY LEFT (-5675 2550);
DISPLAY 1.595745 (-5675 2550);
PAINT SKYBLUE (-5675 2550);
QUIT
